FILE_TYPE = MACRO_DRAWING;
SET COLOR_WIRE YELLOW;
SET COLOR_PROP MONO;
SET COLOR_DOT WHITE;
SET COLOR_ARC YELLOW;
SET COLOR_BODY GREEN;
SET COLOR_NOTE MONO;
SET PROP_DISPLAY VALUE;
SET PAGE_NUMBER P131;
FORCEADD CAP_A..1
(975 4975);
FORCEPROP 1 LAST LOCATION C7B15
J 0
(1025 5075);
DISPLAY 0.617021 (1025 5075);
PAINT AQUA (1025 5075);
FORCEPROP 1 LAST PART_NUMBER E15431-004
J 0
(1025 4825);
DISPLAY 0.617021 (1025 4825);
PAINT BLUE (1025 4825);
FORCEPROP 1 LAST VALUE 22.0UF
J 0
(1025 5025);
DISPLAY 0.617021 (1025 5025);
PAINT SKYBLUE (1025 5025);
FORCEPROP 1 LAST TOLERANCE 20%
J 0
(1025 4925);
DISPLAY 0.617021 (1025 4925);
PAINT SKYBLUE (1025 4925);
FORCEPROP 1 LAST PACK_TYPE 0603V
J 0
(1025 4775);
DISPLAY 0.617021 (1025 4775);
PAINT SKYBLUE (1025 4775);
FORCEPROP 1 LAST VOLTAGE 4V
J 0
(1025 4975);
DISPLAY 0.617021 (1025 4975);
PAINT SKYBLUE (1025 4975);
FORCEPROP 1 LAST MATERIAL X6S
J 0
(1025 4875);
DISPLAY 0.617021 (1025 4875);
PAINT SKYBLUE (1025 4875);
FORCEPROP 2 LAST CDS_LOCATION C7B15
J 0
(1025 5075);
DISPLAY 0.617021 (1025 5075);
PAINT AQUA (1025 5075);
DISPLAY INVISIBLE (1025 5075);
FORCEPROP 2 LAST BOM_COST SB
J 0
(1025 4725);
PAINT MONO (1025 4725);
DISPLAY INVISIBLE (1025 4725);
FORCEPROP 2 LAST CDS_LIB dev_discrete
J 0
(975 4975);
PAINT ORANGE (975 4975);
DISPLAY INVISIBLE (975 4975);
FORCEPROP 2 LAST CDS_SEC 1
J 0
(1025 5175);
DISPLAY 1.361702 (1025 5175);
PAINT ORANGE (1025 5175);
DISPLAY INVISIBLE (1025 5175);
FORCEPROP 2 LAST $SEC 1
J 0
(1025 5175);
DISPLAY 0.914894 (1025 5175);
PAINT MONO (1025 5175);
DISPLAY INVISIBLE (1025 5175);
FORCEPROP 1 LAST PATH I1
J 0
(1025 5125);
DISPLAY 0.978723 (1025 5125);
PAINT WHITE (1025 5125);
DISPLAY INVISIBLE (1025 5125);
FORCEPROP 2 LAST ROOM SB_DECOUPLING
J 0
(975 4975);
PAINT WHITE (975 4975);
DISPLAY INVISIBLE (975 4975);
FORCEPROP 1 LASTPIN (975 5075) $PN 1
J 0
(985 5055);
DISPLAY 1.063830 (985 5055);
PAINT WHITE (985 5055);
DISPLAY INVISIBLE (985 5055);
FORCEPROP 1 LASTPIN (975 4875) $PN 2
J 0
(985 4855);
DISPLAY 1.063830 (985 4855);
PAINT WHITE (985 4855);
DISPLAY INVISIBLE (985 4855);
FORCEADD CAP_A..1
(500 4025);
FORCEPROP 1 LAST LOCATION C7B22
J 0
(550 4125);
DISPLAY 0.617021 (550 4125);
PAINT AQUA (550 4125);
FORCEPROP 1 LAST PART_NUMBER E15431-004
J 0
(550 3875);
DISPLAY 0.617021 (550 3875);
PAINT BLUE (550 3875);
FORCEPROP 1 LAST VALUE 22.0UF
J 0
(550 4075);
DISPLAY 0.617021 (550 4075);
PAINT SKYBLUE (550 4075);
FORCEPROP 1 LAST TOLERANCE 20%
J 0
(550 3975);
DISPLAY 0.617021 (550 3975);
PAINT SKYBLUE (550 3975);
FORCEPROP 1 LAST PACK_TYPE 0603V
J 0
(550 3825);
DISPLAY 0.617021 (550 3825);
PAINT SKYBLUE (550 3825);
FORCEPROP 1 LAST VOLTAGE 4V
J 0
(550 4025);
DISPLAY 0.617021 (550 4025);
PAINT SKYBLUE (550 4025);
FORCEPROP 1 LAST MATERIAL X6S
J 0
(550 3925);
DISPLAY 0.617021 (550 3925);
PAINT SKYBLUE (550 3925);
FORCEPROP 2 LAST CDS_LOCATION C7B22
J 0
(550 4125);
DISPLAY 0.617021 (550 4125);
PAINT AQUA (550 4125);
DISPLAY INVISIBLE (550 4125);
FORCEPROP 2 LAST BOM_COST SB
J 0
(550 3775);
PAINT MONO (550 3775);
DISPLAY INVISIBLE (550 3775);
FORCEPROP 2 LAST CDS_LIB dev_discrete
J 0
(500 4025);
PAINT ORANGE (500 4025);
DISPLAY INVISIBLE (500 4025);
FORCEPROP 2 LAST CDS_SEC 1
J 0
(550 4225);
DISPLAY 1.361702 (550 4225);
PAINT ORANGE (550 4225);
DISPLAY INVISIBLE (550 4225);
FORCEPROP 2 LAST $SEC 1
J 0
(550 4225);
DISPLAY 0.914894 (550 4225);
PAINT MONO (550 4225);
DISPLAY INVISIBLE (550 4225);
FORCEPROP 1 LAST PATH I10
J 0
(550 4175);
DISPLAY 0.978723 (550 4175);
PAINT WHITE (550 4175);
DISPLAY INVISIBLE (550 4175);
FORCEPROP 2 LAST ROOM SB_DECOUPLING
J 0
(500 4025);
PAINT WHITE (500 4025);
DISPLAY INVISIBLE (500 4025);
FORCEPROP 1 LASTPIN (500 4125) $PN 1
J 0
(510 4105);
DISPLAY 1.063830 (510 4105);
PAINT WHITE (510 4105);
DISPLAY INVISIBLE (510 4105);
FORCEPROP 1 LASTPIN (500 3925) $PN 2
J 0
(510 3905);
DISPLAY 1.063830 (510 3905);
PAINT WHITE (510 3905);
DISPLAY INVISIBLE (510 3905);
FORCEADD CAP_A..1
(50 4025);
FORCEPROP 1 LAST LOCATION C7B24
J 0
(100 4125);
DISPLAY 0.617021 (100 4125);
PAINT AQUA (100 4125);
FORCEPROP 1 LAST PART_NUMBER E15431-004
J 0
(100 3875);
DISPLAY 0.617021 (100 3875);
PAINT BLUE (100 3875);
FORCEPROP 1 LAST VALUE 22.0UF
J 0
(100 4075);
DISPLAY 0.617021 (100 4075);
PAINT SKYBLUE (100 4075);
FORCEPROP 1 LAST TOLERANCE 20%
J 0
(100 3975);
DISPLAY 0.617021 (100 3975);
PAINT SKYBLUE (100 3975);
FORCEPROP 1 LAST PACK_TYPE 0603V
J 0
(100 3825);
DISPLAY 0.617021 (100 3825);
PAINT SKYBLUE (100 3825);
FORCEPROP 1 LAST VOLTAGE 4V
J 0
(100 4025);
DISPLAY 0.617021 (100 4025);
PAINT SKYBLUE (100 4025);
FORCEPROP 1 LAST MATERIAL X6S
J 0
(100 3925);
DISPLAY 0.617021 (100 3925);
PAINT SKYBLUE (100 3925);
FORCEPROP 2 LAST CDS_LOCATION C7B24
J 0
(100 4125);
DISPLAY 0.617021 (100 4125);
PAINT AQUA (100 4125);
DISPLAY INVISIBLE (100 4125);
FORCEPROP 2 LAST BOM_COST SB
J 0
(100 3775);
PAINT MONO (100 3775);
DISPLAY INVISIBLE (100 3775);
FORCEPROP 2 LAST CDS_LIB dev_discrete
J 0
(50 4025);
PAINT ORANGE (50 4025);
DISPLAY INVISIBLE (50 4025);
FORCEPROP 2 LAST CDS_SEC 1
J 0
(100 4225);
DISPLAY 1.361702 (100 4225);
PAINT ORANGE (100 4225);
DISPLAY INVISIBLE (100 4225);
FORCEPROP 2 LAST $SEC 1
J 0
(100 4225);
DISPLAY 0.914894 (100 4225);
PAINT MONO (100 4225);
DISPLAY INVISIBLE (100 4225);
FORCEPROP 1 LAST PATH I11
J 0
(100 4175);
DISPLAY 0.978723 (100 4175);
PAINT WHITE (100 4175);
DISPLAY INVISIBLE (100 4175);
FORCEPROP 2 LAST ROOM SB_DECOUPLING
J 0
(50 4025);
PAINT WHITE (50 4025);
DISPLAY INVISIBLE (50 4025);
FORCEPROP 1 LASTPIN (50 4125) $PN 1
J 0
(60 4105);
DISPLAY 1.063830 (60 4105);
PAINT WHITE (60 4105);
DISPLAY INVISIBLE (60 4105);
FORCEPROP 1 LASTPIN (50 3925) $PN 2
J 0
(60 3905);
DISPLAY 1.063830 (60 3905);
PAINT WHITE (60 3905);
DISPLAY INVISIBLE (60 3905);
FORCEADD CAP_A..1
(-425 4025);
FORCEPROP 1 LAST LOCATION C7B18
J 0
(-375 4125);
DISPLAY 0.617021 (-375 4125);
PAINT AQUA (-375 4125);
FORCEPROP 1 LAST PART_NUMBER E15431-004
J 0
(-375 3875);
DISPLAY 0.617021 (-375 3875);
PAINT BLUE (-375 3875);
FORCEPROP 1 LAST VALUE 22.0UF
J 0
(-375 4075);
DISPLAY 0.617021 (-375 4075);
PAINT SKYBLUE (-375 4075);
FORCEPROP 1 LAST TOLERANCE 20%
J 0
(-375 3975);
DISPLAY 0.617021 (-375 3975);
PAINT SKYBLUE (-375 3975);
FORCEPROP 1 LAST PACK_TYPE 0603V
J 0
(-375 3825);
DISPLAY 0.617021 (-375 3825);
PAINT SKYBLUE (-375 3825);
FORCEPROP 1 LAST VOLTAGE 4V
J 0
(-375 4025);
DISPLAY 0.617021 (-375 4025);
PAINT SKYBLUE (-375 4025);
FORCEPROP 1 LAST MATERIAL X6S
J 0
(-375 3925);
DISPLAY 0.617021 (-375 3925);
PAINT SKYBLUE (-375 3925);
FORCEPROP 2 LAST CDS_LOCATION C7B18
J 0
(-375 4125);
DISPLAY 0.617021 (-375 4125);
PAINT AQUA (-375 4125);
DISPLAY INVISIBLE (-375 4125);
FORCEPROP 2 LAST BOM_COST SB
J 0
(-375 3775);
PAINT MONO (-375 3775);
DISPLAY INVISIBLE (-375 3775);
FORCEPROP 2 LAST CDS_LIB dev_discrete
J 0
(-425 4025);
PAINT ORANGE (-425 4025);
DISPLAY INVISIBLE (-425 4025);
FORCEPROP 2 LAST CDS_SEC 1
J 0
(-375 4225);
DISPLAY 1.361702 (-375 4225);
PAINT ORANGE (-375 4225);
DISPLAY INVISIBLE (-375 4225);
FORCEPROP 2 LAST $SEC 1
J 0
(-375 4225);
DISPLAY 0.914894 (-375 4225);
PAINT MONO (-375 4225);
DISPLAY INVISIBLE (-375 4225);
FORCEPROP 1 LAST PATH I12
J 0
(-375 4175);
DISPLAY 0.978723 (-375 4175);
PAINT WHITE (-375 4175);
DISPLAY INVISIBLE (-375 4175);
FORCEPROP 2 LAST ROOM SB_DECOUPLING
J 0
(-425 4025);
PAINT WHITE (-425 4025);
DISPLAY INVISIBLE (-425 4025);
FORCEPROP 1 LASTPIN (-425 4125) $PN 1
J 0
(-415 4105);
DISPLAY 1.063830 (-415 4105);
PAINT WHITE (-415 4105);
DISPLAY INVISIBLE (-415 4105);
FORCEPROP 1 LASTPIN (-425 3925) $PN 2
J 0
(-415 3905);
DISPLAY 1.063830 (-415 3905);
PAINT WHITE (-415 3905);
DISPLAY INVISIBLE (-415 3905);
FORCEADD GND..1
(275 3650);
FORCEPROP 3 LASTPIN (275 3700) SIG_NAME GND\g
J 0
(285 3710);
DISPLAY 0.659574 (285 3710);
PAINT MONO (285 3710);
DISPLAY INVISIBLE (285 3710);
FORCEPROP 1 LAST VOLTAGE 0
J 0
(275 3650);
PAINT SKYBLUE (275 3650);
DISPLAY INVISIBLE (275 3650);
FORCEPROP 1 LAST SIZE 1B
J 0
(350 3600);
DISPLAY 1.404255 (350 3600);
PAINT GREEN (350 3600);
DISPLAY INVISIBLE (350 3600);
FORCEPROP 2 LAST CDS_LIB mstr_symbols
J 0
(275 3650);
PAINT ORANGE (275 3650);
DISPLAY INVISIBLE (275 3650);
FORCEPROP 2 LAST BOM_COST SB
J 0
(225 3725);
PAINT MONO (225 3725);
DISPLAY INVISIBLE (225 3725);
FORCEPROP 1 LAST PATH I13
J 0
(350 3650);
DISPLAY 0.872340 (350 3650);
PAINT AQUA (350 3650);
DISPLAY INVISIBLE (350 3650);
FORCEPROP 2 LAST ROOM SB_DECOUPLING
J 0
(-200 3725);
PAINT WHITE (-200 3725);
DISPLAY INVISIBLE (-200 3725);
FORCEPROP 1 LAST BODY_TYPE PLUMBING
J 0
(230 3607);
DISPLAY 0.340426 (230 3607);
PAINT GREEN (230 3607);
DISPLAY INVISIBLE (230 3607);
FORCEPROP 1 LAST HDL_POWER GND
J 0
(275 3800);
DISPLAY 1.404255 (275 3800);
PAINT GREEN (275 3800);
DISPLAY INVISIBLE (275 3800);
FORCEADD CAP_A..1
(500 3025);
FORCEPROP 1 LAST LOCATION C8B9
J 0
(550 3125);
DISPLAY 0.617021 (550 3125);
PAINT AQUA (550 3125);
FORCEPROP 1 LAST PART_NUMBER E15431-004
J 0
(550 2875);
DISPLAY 0.617021 (550 2875);
PAINT BLUE (550 2875);
FORCEPROP 1 LAST VALUE 22.0UF
J 0
(550 3075);
DISPLAY 0.617021 (550 3075);
PAINT SKYBLUE (550 3075);
FORCEPROP 1 LAST PACK_TYPE 0603V
J 0
(550 2825);
DISPLAY 0.617021 (550 2825);
PAINT SKYBLUE (550 2825);
FORCEPROP 1 LAST VOLTAGE 4V
J 0
(550 3025);
DISPLAY 0.617021 (550 3025);
PAINT SKYBLUE (550 3025);
FORCEPROP 1 LAST MATERIAL X6S
J 0
(550 2925);
DISPLAY 0.617021 (550 2925);
PAINT SKYBLUE (550 2925);
FORCEPROP 1 LASTPIN (500 3125) $PN 1
J 0
(510 3105);
DISPLAY 0.617021 (510 3105);
PAINT WHITE (510 3105);
FORCEPROP 1 LASTPIN (500 2925) $PN 2
J 0
(510 2905);
DISPLAY 0.617021 (510 2905);
PAINT WHITE (510 2905);
FORCEPROP 1 LAST TOLERANCE 20%
J 0
(550 2975);
DISPLAY 0.617021 (550 2975);
PAINT SKYBLUE (550 2975);
FORCEPROP 2 LAST CDS_LOCATION C8B9
J 0
(550 3125);
DISPLAY 0.617021 (550 3125);
PAINT AQUA (550 3125);
DISPLAY INVISIBLE (550 3125);
FORCEPROP 2 LAST BOM_COST SB
J 0
(550 3225);
DISPLAY 1.361702 (550 3225);
PAINT ORANGE (550 3225);
DISPLAY INVISIBLE (550 3225);
FORCEPROP 2 LAST CDS_LIB dev_discrete
J 0
(500 3025);
PAINT ORANGE (500 3025);
DISPLAY INVISIBLE (500 3025);
FORCEPROP 2 LAST CDS_SEC 1
J 0
(550 3225);
DISPLAY 1.361702 (550 3225);
PAINT ORANGE (550 3225);
DISPLAY INVISIBLE (550 3225);
FORCEPROP 2 LAST $SEC 1
J 0
(550 3225);
DISPLAY 0.914894 (550 3225);
PAINT MONO (550 3225);
DISPLAY INVISIBLE (550 3225);
FORCEPROP 1 LAST PATH I14
J 0
(550 3175);
DISPLAY 0.978723 (550 3175);
PAINT WHITE (550 3175);
DISPLAY INVISIBLE (550 3175);
FORCEPROP 2 LAST ROOM SB_DECOUPLING
J 0
(550 3175);
DISPLAY 1.361702 (550 3175);
PAINT ORANGE (550 3175);
DISPLAY INVISIBLE (550 3175);
FORCEADD CAP_A..1
(50 3025);
FORCEPROP 1 LAST LOCATION C8B11
J 0
(100 3125);
DISPLAY 0.617021 (100 3125);
PAINT AQUA (100 3125);
FORCEPROP 1 LAST PART_NUMBER E15431-004
J 0
(100 2875);
DISPLAY 0.617021 (100 2875);
PAINT BLUE (100 2875);
FORCEPROP 1 LAST VALUE 22.0UF
J 0
(100 3075);
DISPLAY 0.617021 (100 3075);
PAINT SKYBLUE (100 3075);
FORCEPROP 1 LAST TOLERANCE 20%
J 0
(100 2975);
DISPLAY 0.617021 (100 2975);
PAINT SKYBLUE (100 2975);
FORCEPROP 1 LAST PACK_TYPE 0603V
J 0
(100 2825);
DISPLAY 0.617021 (100 2825);
PAINT SKYBLUE (100 2825);
FORCEPROP 1 LAST VOLTAGE 4V
J 0
(100 3025);
DISPLAY 0.617021 (100 3025);
PAINT SKYBLUE (100 3025);
FORCEPROP 1 LAST MATERIAL X6S
J 0
(100 2925);
DISPLAY 0.617021 (100 2925);
PAINT SKYBLUE (100 2925);
FORCEPROP 1 LASTPIN (50 3125) $PN 1
J 0
(60 3105);
DISPLAY 0.617021 (60 3105);
PAINT WHITE (60 3105);
FORCEPROP 1 LASTPIN (50 2925) $PN 2
J 0
(60 2905);
DISPLAY 0.617021 (60 2905);
PAINT WHITE (60 2905);
FORCEPROP 2 LAST CDS_LOCATION C8B11
J 0
(100 3125);
DISPLAY 0.617021 (100 3125);
PAINT AQUA (100 3125);
DISPLAY INVISIBLE (100 3125);
FORCEPROP 2 LAST BOM_COST SB
J 0
(100 3225);
DISPLAY 1.361702 (100 3225);
PAINT ORANGE (100 3225);
DISPLAY INVISIBLE (100 3225);
FORCEPROP 2 LAST CDS_LIB dev_discrete
J 0
(50 3025);
PAINT ORANGE (50 3025);
DISPLAY INVISIBLE (50 3025);
FORCEPROP 2 LAST CDS_SEC 1
J 0
(100 3225);
DISPLAY 1.361702 (100 3225);
PAINT ORANGE (100 3225);
DISPLAY INVISIBLE (100 3225);
FORCEPROP 2 LAST $SEC 1
J 0
(100 3225);
DISPLAY 0.914894 (100 3225);
PAINT MONO (100 3225);
DISPLAY INVISIBLE (100 3225);
FORCEPROP 1 LAST PATH I15
J 0
(100 3175);
DISPLAY 0.978723 (100 3175);
PAINT WHITE (100 3175);
DISPLAY INVISIBLE (100 3175);
FORCEPROP 2 LAST ROOM SB_DECOUPLING
J 0
(100 3175);
DISPLAY 1.361702 (100 3175);
PAINT ORANGE (100 3175);
DISPLAY INVISIBLE (100 3175);
FORCEADD CAP_A..1
(-400 3025);
FORCEPROP 1 LAST LOCATION C8B14
J 0
(-350 3125);
DISPLAY 0.617021 (-350 3125);
PAINT AQUA (-350 3125);
FORCEPROP 1 LAST PART_NUMBER E15431-004
J 0
(-350 2875);
DISPLAY 0.617021 (-350 2875);
PAINT BLUE (-350 2875);
FORCEPROP 1 LAST VALUE 22.0UF
J 0
(-350 3075);
DISPLAY 0.617021 (-350 3075);
PAINT SKYBLUE (-350 3075);
FORCEPROP 1 LAST TOLERANCE 20%
J 0
(-350 2975);
DISPLAY 0.617021 (-350 2975);
PAINT SKYBLUE (-350 2975);
FORCEPROP 1 LAST PACK_TYPE 0603V
J 0
(-350 2825);
DISPLAY 0.617021 (-350 2825);
PAINT SKYBLUE (-350 2825);
FORCEPROP 1 LAST VOLTAGE 4V
J 0
(-350 3025);
DISPLAY 0.617021 (-350 3025);
PAINT SKYBLUE (-350 3025);
FORCEPROP 1 LAST MATERIAL X6S
J 0
(-350 2925);
DISPLAY 0.617021 (-350 2925);
PAINT SKYBLUE (-350 2925);
FORCEPROP 1 LASTPIN (-400 3125) $PN 1
J 0
(-390 3105);
DISPLAY 0.617021 (-390 3105);
PAINT WHITE (-390 3105);
FORCEPROP 1 LASTPIN (-400 2925) $PN 2
J 0
(-390 2905);
DISPLAY 0.617021 (-390 2905);
PAINT WHITE (-390 2905);
FORCEPROP 2 LAST CDS_LOCATION C8B14
J 0
(-350 3125);
DISPLAY 0.617021 (-350 3125);
PAINT AQUA (-350 3125);
DISPLAY INVISIBLE (-350 3125);
FORCEPROP 2 LAST BOM_COST SB
J 0
(-350 3225);
DISPLAY 1.361702 (-350 3225);
PAINT ORANGE (-350 3225);
DISPLAY INVISIBLE (-350 3225);
FORCEPROP 2 LAST CDS_LIB dev_discrete
J 0
(-400 3025);
PAINT ORANGE (-400 3025);
DISPLAY INVISIBLE (-400 3025);
FORCEPROP 2 LAST CDS_SEC 1
J 0
(-350 3225);
DISPLAY 1.361702 (-350 3225);
PAINT ORANGE (-350 3225);
DISPLAY INVISIBLE (-350 3225);
FORCEPROP 2 LAST $SEC 1
J 0
(-350 3225);
DISPLAY 0.914894 (-350 3225);
PAINT MONO (-350 3225);
DISPLAY INVISIBLE (-350 3225);
FORCEPROP 1 LAST PATH I16
J 0
(-350 3175);
DISPLAY 0.978723 (-350 3175);
PAINT WHITE (-350 3175);
DISPLAY INVISIBLE (-350 3175);
FORCEPROP 2 LAST ROOM SB_DECOUPLING
J 0
(-350 3175);
DISPLAY 1.361702 (-350 3175);
PAINT ORANGE (-350 3175);
DISPLAY INVISIBLE (-350 3175);
FORCEADD P1V05_PCH_STBY..1
(-625 4300);
FORCEPROP 3 LASTPIN (-625 4250) SIG_NAME P1V05_PCH_STBY\g
J 0
(-615 4260);
DISPLAY 0.659574 (-615 4260);
PAINT MONO (-615 4260);
DISPLAY INVISIBLE (-615 4260);
FORCEPROP 1 LAST VOLTAGE 1.05V
J 0
(-670 4257);
DISPLAY 0.340426 (-670 4257);
PAINT SKYBLUE (-670 4257);
DISPLAY INVISIBLE (-670 4257);
FORCEPROP 2 LAST BOM_COST SB
J 0
(-625 4450);
PAINT MONO (-625 4450);
DISPLAY INVISIBLE (-625 4450);
FORCEPROP 2 LAST CDS_LIB mstr_symbols
J 0
(-625 4300);
PAINT ORANGE (-625 4300);
DISPLAY INVISIBLE (-625 4300);
FORCEPROP 1 LAST PATH I17
J 0
(-575 4325);
DISPLAY 0.872340 (-575 4325);
PAINT AQUA (-575 4325);
DISPLAY INVISIBLE (-575 4325);
FORCEPROP 2 LAST ROOM SB_DECOUPLING
J 0
(-625 4400);
DISPLAY 1.361702 (-625 4400);
PAINT WHITE (-625 4400);
DISPLAY INVISIBLE (-625 4400);
FORCEPROP 1 LAST BODY_TYPE PLUMBING
J 0
(-670 4257);
DISPLAY 0.340426 (-670 4257);
PAINT GREEN (-670 4257);
DISPLAY INVISIBLE (-670 4257);
FORCEPROP 1 LAST HDL_POWER P1V05_PCH_STBY
J 0
(-625 4350);
DISPLAY 0.872340 (-625 4350);
PAINT GREEN (-625 4350);
DISPLAY INVISIBLE (-625 4350);
FORCEADD CAP_A..1
(-875 4025);
FORCEPROP 1 LAST LOCATION C7B17
J 0
(-825 4125);
DISPLAY 0.617021 (-825 4125);
PAINT AQUA (-825 4125);
FORCEPROP 1 LAST PART_NUMBER E15431-004
J 0
(-825 3875);
DISPLAY 0.617021 (-825 3875);
PAINT BLUE (-825 3875);
FORCEPROP 1 LAST VALUE 22.0UF
J 0
(-825 4075);
DISPLAY 0.617021 (-825 4075);
PAINT SKYBLUE (-825 4075);
FORCEPROP 1 LAST TOLERANCE 20%
J 0
(-825 3975);
DISPLAY 0.617021 (-825 3975);
PAINT SKYBLUE (-825 3975);
FORCEPROP 1 LAST PACK_TYPE 0603V
J 0
(-825 3825);
DISPLAY 0.617021 (-825 3825);
PAINT SKYBLUE (-825 3825);
FORCEPROP 1 LAST VOLTAGE 4V
J 0
(-825 4025);
DISPLAY 0.617021 (-825 4025);
PAINT SKYBLUE (-825 4025);
FORCEPROP 1 LAST MATERIAL X6S
J 0
(-825 3925);
DISPLAY 0.617021 (-825 3925);
PAINT SKYBLUE (-825 3925);
FORCEPROP 2 LAST CDS_LOCATION C7B17
J 0
(-825 4125);
DISPLAY 0.617021 (-825 4125);
PAINT AQUA (-825 4125);
DISPLAY INVISIBLE (-825 4125);
FORCEPROP 2 LAST BOM_COST SB
J 0
(-825 3775);
PAINT MONO (-825 3775);
DISPLAY INVISIBLE (-825 3775);
FORCEPROP 2 LAST CDS_LIB dev_discrete
J 0
(-875 4025);
PAINT ORANGE (-875 4025);
DISPLAY INVISIBLE (-875 4025);
FORCEPROP 2 LAST CDS_SEC 1
J 0
(-825 4225);
DISPLAY 1.361702 (-825 4225);
PAINT ORANGE (-825 4225);
DISPLAY INVISIBLE (-825 4225);
FORCEPROP 2 LAST $SEC 1
J 0
(-825 4225);
DISPLAY 0.914894 (-825 4225);
PAINT MONO (-825 4225);
DISPLAY INVISIBLE (-825 4225);
FORCEPROP 1 LAST PATH I18
J 0
(-825 4175);
DISPLAY 0.978723 (-825 4175);
PAINT WHITE (-825 4175);
DISPLAY INVISIBLE (-825 4175);
FORCEPROP 2 LAST ROOM SB_DECOUPLING
J 0
(-875 4025);
PAINT WHITE (-875 4025);
DISPLAY INVISIBLE (-875 4025);
FORCEPROP 1 LASTPIN (-875 4125) $PN 1
J 0
(-865 4105);
DISPLAY 1.063830 (-865 4105);
PAINT WHITE (-865 4105);
DISPLAY INVISIBLE (-865 4105);
FORCEPROP 1 LASTPIN (-875 3925) $PN 2
J 0
(-865 3905);
DISPLAY 1.063830 (-865 3905);
PAINT WHITE (-865 3905);
DISPLAY INVISIBLE (-865 3905);
FORCEADD P1V05_PCH_STBY..1
(-625 3325);
FORCEPROP 3 LASTPIN (-625 3275) SIG_NAME P1V05_PCH_STBY\g
J 0
(-615 3285);
DISPLAY 0.659574 (-615 3285);
PAINT MONO (-615 3285);
DISPLAY INVISIBLE (-615 3285);
FORCEPROP 1 LAST VOLTAGE 1.05V
J 0
(-670 3282);
DISPLAY 0.340426 (-670 3282);
PAINT SKYBLUE (-670 3282);
DISPLAY INVISIBLE (-670 3282);
FORCEPROP 2 LAST BOM_COST SB
J 0
(-625 3425);
DISPLAY 1.361702 (-625 3425);
PAINT ORANGE (-625 3425);
DISPLAY INVISIBLE (-625 3425);
FORCEPROP 2 LAST CDS_LIB mstr_symbols
J 0
(-625 3325);
PAINT ORANGE (-625 3325);
DISPLAY INVISIBLE (-625 3325);
FORCEPROP 1 LAST PATH I19
J 0
(-575 3350);
DISPLAY 0.872340 (-575 3350);
PAINT AQUA (-575 3350);
DISPLAY INVISIBLE (-575 3350);
FORCEPROP 2 LAST ROOM SB_DECOUPLING
J 0
(-625 3425);
DISPLAY 1.361702 (-625 3425);
PAINT ORANGE (-625 3425);
DISPLAY INVISIBLE (-625 3425);
FORCEPROP 1 LAST BODY_TYPE PLUMBING
J 0
(-670 3282);
DISPLAY 0.340426 (-670 3282);
PAINT GREEN (-670 3282);
DISPLAY INVISIBLE (-670 3282);
FORCEPROP 1 LAST HDL_POWER P1V05_PCH_STBY
J 0
(-625 3375);
DISPLAY 0.872340 (-625 3375);
PAINT GREEN (-625 3375);
DISPLAY INVISIBLE (-625 3375);
FORCEADD CAP_A..1
(500 4975);
FORCEPROP 1 LAST LOCATION C7B19
J 0
(550 5075);
DISPLAY 0.617021 (550 5075);
PAINT AQUA (550 5075);
FORCEPROP 1 LAST PART_NUMBER E15431-004
J 0
(550 4825);
DISPLAY 0.617021 (550 4825);
PAINT BLUE (550 4825);
FORCEPROP 1 LAST VALUE 22.0UF
J 0
(550 5025);
DISPLAY 0.617021 (550 5025);
PAINT SKYBLUE (550 5025);
FORCEPROP 1 LAST TOLERANCE 20%
J 0
(550 4925);
DISPLAY 0.617021 (550 4925);
PAINT SKYBLUE (550 4925);
FORCEPROP 1 LAST PACK_TYPE 0603V
J 0
(550 4775);
DISPLAY 0.617021 (550 4775);
PAINT SKYBLUE (550 4775);
FORCEPROP 1 LAST VOLTAGE 4V
J 0
(550 4975);
DISPLAY 0.617021 (550 4975);
PAINT SKYBLUE (550 4975);
FORCEPROP 1 LAST MATERIAL X6S
J 0
(550 4875);
DISPLAY 0.617021 (550 4875);
PAINT SKYBLUE (550 4875);
FORCEPROP 2 LAST CDS_LOCATION C7B19
J 0
(550 5075);
DISPLAY 0.617021 (550 5075);
PAINT AQUA (550 5075);
DISPLAY INVISIBLE (550 5075);
FORCEPROP 2 LAST BOM_COST SB
J 0
(550 4725);
PAINT MONO (550 4725);
DISPLAY INVISIBLE (550 4725);
FORCEPROP 2 LAST CDS_LIB dev_discrete
J 0
(500 4975);
PAINT ORANGE (500 4975);
DISPLAY INVISIBLE (500 4975);
FORCEPROP 2 LAST CDS_SEC 1
J 0
(550 5175);
DISPLAY 1.361702 (550 5175);
PAINT ORANGE (550 5175);
DISPLAY INVISIBLE (550 5175);
FORCEPROP 2 LAST $SEC 1
J 0
(550 5175);
DISPLAY 0.914894 (550 5175);
PAINT MONO (550 5175);
DISPLAY INVISIBLE (550 5175);
FORCEPROP 1 LAST PATH I2
J 0
(550 5125);
DISPLAY 0.978723 (550 5125);
PAINT WHITE (550 5125);
DISPLAY INVISIBLE (550 5125);
FORCEPROP 2 LAST ROOM SB_DECOUPLING
J 0
(500 4975);
PAINT WHITE (500 4975);
DISPLAY INVISIBLE (500 4975);
FORCEPROP 1 LASTPIN (500 5075) $PN 1
J 0
(510 5055);
DISPLAY 1.063830 (510 5055);
PAINT WHITE (510 5055);
DISPLAY INVISIBLE (510 5055);
FORCEPROP 1 LASTPIN (500 4875) $PN 2
J 0
(510 4855);
DISPLAY 1.063830 (510 4855);
PAINT WHITE (510 4855);
DISPLAY INVISIBLE (510 4855);
FORCEADD CAP_A..1
(-850 3025);
FORCEPROP 1 LAST LOCATION C8B13
J 0
(-800 3125);
DISPLAY 0.617021 (-800 3125);
PAINT AQUA (-800 3125);
FORCEPROP 1 LAST PART_NUMBER E15431-004
J 0
(-800 2875);
DISPLAY 0.617021 (-800 2875);
PAINT BLUE (-800 2875);
FORCEPROP 1 LAST VALUE 22.0UF
J 0
(-800 3075);
DISPLAY 0.617021 (-800 3075);
PAINT SKYBLUE (-800 3075);
FORCEPROP 1 LAST TOLERANCE 20%
J 0
(-800 2975);
DISPLAY 0.617021 (-800 2975);
PAINT SKYBLUE (-800 2975);
FORCEPROP 1 LAST PACK_TYPE 0603V
J 0
(-800 2825);
DISPLAY 0.617021 (-800 2825);
PAINT SKYBLUE (-800 2825);
FORCEPROP 1 LAST VOLTAGE 4V
J 0
(-800 3025);
DISPLAY 0.617021 (-800 3025);
PAINT SKYBLUE (-800 3025);
FORCEPROP 1 LAST MATERIAL X6S
J 0
(-800 2925);
DISPLAY 0.617021 (-800 2925);
PAINT SKYBLUE (-800 2925);
FORCEPROP 1 LASTPIN (-850 3125) $PN 1
J 0
(-840 3105);
DISPLAY 0.617021 (-840 3105);
PAINT WHITE (-840 3105);
FORCEPROP 1 LASTPIN (-850 2925) $PN 2
J 0
(-840 2905);
DISPLAY 0.617021 (-840 2905);
PAINT WHITE (-840 2905);
FORCEPROP 2 LAST CDS_LOCATION C8B13
J 0
(-800 3125);
DISPLAY 0.617021 (-800 3125);
PAINT AQUA (-800 3125);
DISPLAY INVISIBLE (-800 3125);
FORCEPROP 2 LAST BOM_COST SB
J 0
(-800 3225);
DISPLAY 1.361702 (-800 3225);
PAINT ORANGE (-800 3225);
DISPLAY INVISIBLE (-800 3225);
FORCEPROP 2 LAST CDS_LIB dev_discrete
J 0
(-850 3025);
PAINT ORANGE (-850 3025);
DISPLAY INVISIBLE (-850 3025);
FORCEPROP 2 LAST CDS_SEC 1
J 0
(-800 3225);
DISPLAY 1.361702 (-800 3225);
PAINT ORANGE (-800 3225);
DISPLAY INVISIBLE (-800 3225);
FORCEPROP 2 LAST $SEC 1
J 0
(-800 3225);
DISPLAY 0.914894 (-800 3225);
PAINT MONO (-800 3225);
DISPLAY INVISIBLE (-800 3225);
FORCEPROP 1 LAST PATH I20
J 0
(-800 3175);
DISPLAY 0.978723 (-800 3175);
PAINT WHITE (-800 3175);
DISPLAY INVISIBLE (-800 3175);
FORCEPROP 2 LAST ROOM SB_DECOUPLING
J 0
(-800 3175);
DISPLAY 1.361702 (-800 3175);
PAINT ORANGE (-800 3175);
DISPLAY INVISIBLE (-800 3175);
FORCEADD GND..1
(275 2675);
FORCEPROP 3 LASTPIN (275 2725) SIG_NAME GND\g
J 0
(285 2735);
DISPLAY 0.659574 (285 2735);
PAINT MONO (285 2735);
DISPLAY INVISIBLE (285 2735);
FORCEPROP 1 LAST VOLTAGE 0.0V
J 0
(230 2632);
DISPLAY 0.340426 (230 2632);
PAINT SKYBLUE (230 2632);
DISPLAY INVISIBLE (230 2632);
FORCEPROP 1 LAST SIZE 1B
J 0
(350 2625);
DISPLAY 1.170213 (350 2625);
PAINT AQUA (350 2625);
DISPLAY INVISIBLE (350 2625);
FORCEPROP 2 LAST CDS_LIB mstr_symbols
J 0
(275 2675);
PAINT MONO (275 2675);
DISPLAY INVISIBLE (275 2675);
FORCEPROP 2 LAST BOM_COST SB
J 0
(300 2750);
DISPLAY 1.361702 (300 2750);
PAINT ORANGE (300 2750);
DISPLAY INVISIBLE (300 2750);
FORCEPROP 1 LAST PATH I21
J 0
(350 2675);
DISPLAY 0.872340 (350 2675);
PAINT AQUA (350 2675);
DISPLAY INVISIBLE (350 2675);
FORCEPROP 2 LAST ROOM SB_DECOUPLING
J 0
(300 2750);
DISPLAY 1.361702 (300 2750);
PAINT ORANGE (300 2750);
DISPLAY INVISIBLE (300 2750);
FORCEPROP 1 LAST BODY_TYPE PLUMBING
J 0
(230 2632);
DISPLAY 0.340426 (230 2632);
PAINT GREEN (230 2632);
DISPLAY INVISIBLE (230 2632);
FORCEPROP 1 LAST HDL_POWER GND
J 0
(275 2825);
DISPLAY 1.170213 (275 2825);
PAINT GREEN (275 2825);
DISPLAY INVISIBLE (275 2825);
FORCEADD CAP..1
(50 2025);
FORCEPROP 1 LAST LOCATION C8B16
J 0
(100 2125);
DISPLAY 0.617021 (100 2125);
PAINT AQUA (100 2125);
FORCEPROP 1 LAST PART_NUMBER C95333-006
J 0
(100 1875);
DISPLAY 0.617021 (100 1875);
PAINT BLUE (100 1875);
FORCEPROP 1 LAST VALUE 47UF
J 0
(100 2075);
DISPLAY 0.617021 (100 2075);
PAINT SKYBLUE (100 2075);
FORCEPROP 1 LAST TOLERANCE 20%
J 0
(100 1975);
DISPLAY 0.617021 (100 1975);
PAINT SKYBLUE (100 1975);
FORCEPROP 1 LAST PACK_TYPE 0805
J 0
(100 1825);
DISPLAY 0.617021 (100 1825);
PAINT SKYBLUE (100 1825);
FORCEPROP 1 LAST VOLTAGE 4V
J 0
(100 2025);
DISPLAY 0.617021 (100 2025);
PAINT SKYBLUE (100 2025);
FORCEPROP 1 LAST MATERIAL X6S
J 0
(100 1925);
DISPLAY 0.617021 (100 1925);
PAINT SKYBLUE (100 1925);
FORCEPROP 1 LASTPIN (50 1925) $PN 2
J 0
(60 1905);
DISPLAY 0.617021 (60 1905);
PAINT WHITE (60 1905);
FORCEPROP 1 LASTPIN (50 2125) $PN 1
J 0
(60 2105);
DISPLAY 0.617021 (60 2105);
PAINT WHITE (60 2105);
FORCEPROP 2 LAST BOM_COST SB
J 0
(100 2225);
DISPLAY 1.361702 (100 2225);
PAINT ORANGE (100 2225);
DISPLAY INVISIBLE (100 2225);
FORCEPROP 2 LAST CDS_LIB mstr_discrete
J 0
(50 2025);
PAINT MONO (50 2025);
DISPLAY INVISIBLE (50 2025);
FORCEPROP 2 LAST CDS_SEC 1
J 0
(100 2225);
DISPLAY 1.361702 (100 2225);
PAINT ORANGE (100 2225);
DISPLAY INVISIBLE (100 2225);
FORCEPROP 2 LAST $SEC 1
J 0
(100 2225);
DISPLAY 0.914894 (100 2225);
PAINT MONO (100 2225);
DISPLAY INVISIBLE (100 2225);
FORCEPROP 2 LAST CDS_LOCATION C8B16
J 0
(100 2125);
DISPLAY 0.617021 (100 2125);
PAINT AQUA (100 2125);
DISPLAY INVISIBLE (100 2125);
FORCEPROP 1 LAST PATH I22
J 0
(100 2175);
DISPLAY 0.978723 (100 2175);
PAINT WHITE (100 2175);
DISPLAY INVISIBLE (100 2175);
FORCEPROP 2 LAST ROOM SB_DECOUPLING
J 0
(100 2175);
DISPLAY 1.361702 (100 2175);
PAINT ORANGE (100 2175);
DISPLAY INVISIBLE (100 2175);
FORCEADD P1V05_PCH_STBY..1
(-175 2325);
FORCEPROP 3 LASTPIN (-175 2275) SIG_NAME P1V05_PCH_STBY\g
J 0
(-165 2285);
DISPLAY 0.659574 (-165 2285);
PAINT MONO (-165 2285);
DISPLAY INVISIBLE (-165 2285);
FORCEPROP 1 LAST VOLTAGE 1.05V
J 0
(-220 2282);
DISPLAY 0.340426 (-220 2282);
PAINT SKYBLUE (-220 2282);
DISPLAY INVISIBLE (-220 2282);
FORCEPROP 2 LAST BOM_COST SB
J 0
(-175 2425);
DISPLAY 1.361702 (-175 2425);
PAINT ORANGE (-175 2425);
DISPLAY INVISIBLE (-175 2425);
FORCEPROP 2 LAST CDS_LIB mstr_symbols
J 0
(-175 2325);
PAINT ORANGE (-175 2325);
DISPLAY INVISIBLE (-175 2325);
FORCEPROP 1 LAST PATH I23
J 0
(-125 2350);
DISPLAY 0.872340 (-125 2350);
PAINT AQUA (-125 2350);
DISPLAY INVISIBLE (-125 2350);
FORCEPROP 2 LAST ROOM SB_DECOUPLING
J 0
(-175 2425);
DISPLAY 1.361702 (-175 2425);
PAINT ORANGE (-175 2425);
DISPLAY INVISIBLE (-175 2425);
FORCEPROP 1 LAST BODY_TYPE PLUMBING
J 0
(-220 2282);
DISPLAY 0.340426 (-220 2282);
PAINT GREEN (-220 2282);
DISPLAY INVISIBLE (-220 2282);
FORCEPROP 1 LAST HDL_POWER P1V05_PCH_STBY
J 0
(-175 2375);
DISPLAY 0.872340 (-175 2375);
PAINT GREEN (-175 2375);
DISPLAY INVISIBLE (-175 2375);
FORCEADD CAP..1
(-400 2025);
FORCEPROP 1 LAST LOCATION C8B15
J 0
(-350 2125);
DISPLAY 0.617021 (-350 2125);
PAINT AQUA (-350 2125);
FORCEPROP 1 LAST PART_NUMBER C95333-006
J 0
(-350 1875);
DISPLAY 0.617021 (-350 1875);
PAINT BLUE (-350 1875);
FORCEPROP 1 LAST VALUE 47UF
J 0
(-350 2075);
DISPLAY 0.617021 (-350 2075);
PAINT SKYBLUE (-350 2075);
FORCEPROP 1 LAST TOLERANCE 20%
J 0
(-350 1975);
DISPLAY 0.617021 (-350 1975);
PAINT SKYBLUE (-350 1975);
FORCEPROP 1 LAST PACK_TYPE 0805
J 0
(-350 1825);
DISPLAY 0.617021 (-350 1825);
PAINT SKYBLUE (-350 1825);
FORCEPROP 1 LAST VOLTAGE 4V
J 0
(-350 2025);
DISPLAY 0.617021 (-350 2025);
PAINT SKYBLUE (-350 2025);
FORCEPROP 1 LAST MATERIAL X6S
J 0
(-350 1925);
DISPLAY 0.617021 (-350 1925);
PAINT SKYBLUE (-350 1925);
FORCEPROP 1 LASTPIN (-400 1925) $PN 2
J 0
(-390 1905);
DISPLAY 0.617021 (-390 1905);
PAINT WHITE (-390 1905);
FORCEPROP 1 LASTPIN (-400 2125) $PN 1
J 0
(-390 2105);
DISPLAY 0.617021 (-390 2105);
PAINT WHITE (-390 2105);
FORCEPROP 2 LAST BOM_COST SB
J 0
(-350 2225);
DISPLAY 1.361702 (-350 2225);
PAINT ORANGE (-350 2225);
DISPLAY INVISIBLE (-350 2225);
FORCEPROP 2 LAST CDS_LIB mstr_discrete
J 0
(-400 2025);
PAINT MONO (-400 2025);
DISPLAY INVISIBLE (-400 2025);
FORCEPROP 2 LAST CDS_SEC 1
J 0
(-350 2225);
DISPLAY 1.361702 (-350 2225);
PAINT ORANGE (-350 2225);
DISPLAY INVISIBLE (-350 2225);
FORCEPROP 2 LAST $SEC 1
J 0
(-350 2225);
DISPLAY 0.914894 (-350 2225);
PAINT MONO (-350 2225);
DISPLAY INVISIBLE (-350 2225);
FORCEPROP 2 LAST CDS_LOCATION C8B15
J 0
(-350 2125);
DISPLAY 0.617021 (-350 2125);
PAINT AQUA (-350 2125);
DISPLAY INVISIBLE (-350 2125);
FORCEPROP 1 LAST PATH I24
J 0
(-350 2175);
DISPLAY 0.978723 (-350 2175);
PAINT WHITE (-350 2175);
DISPLAY INVISIBLE (-350 2175);
FORCEPROP 2 LAST ROOM SB_DECOUPLING
J 0
(-350 2175);
DISPLAY 1.361702 (-350 2175);
PAINT ORANGE (-350 2175);
DISPLAY INVISIBLE (-350 2175);
FORCEADD GND..1
(-175 1650);
FORCEPROP 3 LASTPIN (-175 1700) SIG_NAME GND\g
J 0
(-165 1710);
DISPLAY 0.659574 (-165 1710);
PAINT MONO (-165 1710);
DISPLAY INVISIBLE (-165 1710);
FORCEPROP 1 LAST VOLTAGE 0.0V
J 0
(-220 1607);
DISPLAY 0.340426 (-220 1607);
PAINT SKYBLUE (-220 1607);
DISPLAY INVISIBLE (-220 1607);
FORCEPROP 1 LAST SIZE 1B
J 0
(-100 1600);
DISPLAY 1.170213 (-100 1600);
PAINT AQUA (-100 1600);
DISPLAY INVISIBLE (-100 1600);
FORCEPROP 2 LAST CDS_LIB mstr_symbols
J 0
(-175 1650);
PAINT MONO (-175 1650);
DISPLAY INVISIBLE (-175 1650);
FORCEPROP 2 LAST BOM_COST SB
J 0
(-150 1725);
DISPLAY 1.361702 (-150 1725);
PAINT ORANGE (-150 1725);
DISPLAY INVISIBLE (-150 1725);
FORCEPROP 1 LAST PATH I25
J 0
(-100 1650);
DISPLAY 0.872340 (-100 1650);
PAINT AQUA (-100 1650);
DISPLAY INVISIBLE (-100 1650);
FORCEPROP 2 LAST ROOM SB_DECOUPLING
J 0
(-150 1725);
DISPLAY 1.361702 (-150 1725);
PAINT ORANGE (-150 1725);
DISPLAY INVISIBLE (-150 1725);
FORCEPROP 1 LAST BODY_TYPE PLUMBING
J 0
(-220 1607);
DISPLAY 0.340426 (-220 1607);
PAINT GREEN (-220 1607);
DISPLAY INVISIBLE (-220 1607);
FORCEPROP 1 LAST HDL_POWER GND
J 0
(-175 1800);
DISPLAY 1.170213 (-175 1800);
PAINT GREEN (-175 1800);
DISPLAY INVISIBLE (-175 1800);
FORCEADD P1V05_PCH_STBY..1
(-4575 5000);
FORCEPROP 3 LASTPIN (-4575 4950) SIG_NAME P1V05_PCH_STBY\g
J 0
(-4565 4960);
DISPLAY 0.659574 (-4565 4960);
PAINT MONO (-4565 4960);
DISPLAY INVISIBLE (-4565 4960);
FORCEPROP 1 LAST VOLTAGE 1.05V
J 0
(-4620 4957);
DISPLAY 0.340426 (-4620 4957);
PAINT SKYBLUE (-4620 4957);
DISPLAY INVISIBLE (-4620 4957);
FORCEPROP 2 LAST BOM_COST SB
J 0
(-4575 5150);
PAINT MONO (-4575 5150);
DISPLAY INVISIBLE (-4575 5150);
FORCEPROP 2 LAST CDS_LIB mstr_symbols
J 0
(-4575 5000);
PAINT ORANGE (-4575 5000);
DISPLAY INVISIBLE (-4575 5000);
FORCEPROP 1 LAST PATH I26
J 0
(-4525 5025);
DISPLAY 0.872340 (-4525 5025);
PAINT AQUA (-4525 5025);
DISPLAY INVISIBLE (-4525 5025);
FORCEPROP 2 LAST ROOM SB_DECOUPLING
J 0
(-4575 5100);
DISPLAY 1.361702 (-4575 5100);
PAINT WHITE (-4575 5100);
DISPLAY INVISIBLE (-4575 5100);
FORCEPROP 1 LAST BODY_TYPE PLUMBING
J 0
(-4620 4957);
DISPLAY 0.340426 (-4620 4957);
PAINT GREEN (-4620 4957);
DISPLAY INVISIBLE (-4620 4957);
FORCEPROP 1 LAST HDL_POWER P1V05_PCH_STBY
J 0
(-4575 5050);
DISPLAY 0.872340 (-4575 5050);
PAINT GREEN (-4575 5050);
DISPLAY INVISIBLE (-4575 5050);
FORCEADD CAP_A..1
(-2375 4725);
FORCEPROP 1 LAST LOCATION C2M22
J 0
(-2325 4825);
DISPLAY 0.617021 (-2325 4825);
PAINT AQUA (-2325 4825);
FORCEPROP 1 LAST PART_NUMBER D97712-004
J 0
(-2325 4575);
DISPLAY 0.617021 (-2325 4575);
PAINT BLUE (-2325 4575);
FORCEPROP 1 LAST VALUE 1.0UF
J 0
(-2325 4775);
DISPLAY 0.617021 (-2325 4775);
PAINT SKYBLUE (-2325 4775);
FORCEPROP 1 LAST TOLERANCE 10%
J 0
(-2325 4675);
DISPLAY 0.617021 (-2325 4675);
PAINT SKYBLUE (-2325 4675);
FORCEPROP 1 LAST PACK_TYPE 0402V
J 0
(-2325 4525);
DISPLAY 0.617021 (-2325 4525);
PAINT SKYBLUE (-2325 4525);
FORCEPROP 1 LAST VOLTAGE 6.3V
J 0
(-2325 4725);
DISPLAY 0.617021 (-2325 4725);
PAINT SKYBLUE (-2325 4725);
FORCEPROP 1 LAST MATERIAL X6S
J 0
(-2325 4625);
DISPLAY 0.617021 (-2325 4625);
PAINT SKYBLUE (-2325 4625);
FORCEPROP 1 LASTPIN (-2375 4825) $PN 1
J 0
(-2365 4805);
DISPLAY 0.617021 (-2365 4805);
PAINT ORANGE (-2365 4805);
FORCEPROP 1 LASTPIN (-2375 4625) $PN 2
J 0
(-2365 4605);
DISPLAY 0.617021 (-2365 4605);
PAINT ORANGE (-2365 4605);
FORCEPROP 2 LAST CDS_LOCATION C2M22
J 0
(-2325 4825);
DISPLAY 0.617021 (-2325 4825);
PAINT AQUA (-2325 4825);
DISPLAY INVISIBLE (-2325 4825);
FORCEPROP 2 LAST BOM_COST SB
J 0
(-2325 4475);
PAINT MONO (-2325 4475);
DISPLAY INVISIBLE (-2325 4475);
FORCEPROP 2 LAST CDS_LIB dev_discrete
J 0
(-2375 4725);
PAINT ORANGE (-2375 4725);
DISPLAY INVISIBLE (-2375 4725);
FORCEPROP 2 LAST CDS_SEC 1
J 0
(-2325 4925);
PAINT MONO (-2325 4925);
DISPLAY INVISIBLE (-2325 4925);
FORCEPROP 2 LAST $SEC 1
J 0
(-2325 4925);
PAINT MONO (-2325 4925);
DISPLAY INVISIBLE (-2325 4925);
FORCEPROP 1 LAST PATH I27
J 0
(-2325 4875);
DISPLAY 0.978723 (-2325 4875);
PAINT WHITE (-2325 4875);
DISPLAY INVISIBLE (-2325 4875);
FORCEPROP 2 LAST ROOM SB_DECOUPLING
J 0
(-2375 4725);
PAINT WHITE (-2375 4725);
DISPLAY INVISIBLE (-2375 4725);
FORCEADD CAP_A..1
(-2800 4725);
FORCEPROP 1 LAST LOCATION C2M21
J 0
(-2750 4825);
DISPLAY 0.617021 (-2750 4825);
PAINT AQUA (-2750 4825);
FORCEPROP 1 LAST PART_NUMBER D97712-004
J 0
(-2750 4575);
DISPLAY 0.617021 (-2750 4575);
PAINT BLUE (-2750 4575);
FORCEPROP 1 LAST VALUE 1.0UF
J 0
(-2750 4775);
DISPLAY 0.617021 (-2750 4775);
PAINT SKYBLUE (-2750 4775);
FORCEPROP 1 LAST TOLERANCE 10%
J 0
(-2750 4675);
DISPLAY 0.617021 (-2750 4675);
PAINT SKYBLUE (-2750 4675);
FORCEPROP 1 LAST PACK_TYPE 0402V
J 0
(-2750 4525);
DISPLAY 0.617021 (-2750 4525);
PAINT SKYBLUE (-2750 4525);
FORCEPROP 1 LAST VOLTAGE 6.3V
J 0
(-2750 4725);
DISPLAY 0.617021 (-2750 4725);
PAINT SKYBLUE (-2750 4725);
FORCEPROP 1 LASTPIN (-2800 4825) $PN 1
J 0
(-2790 4805);
DISPLAY 0.617021 (-2790 4805);
PAINT WHITE (-2790 4805);
FORCEPROP 1 LASTPIN (-2800 4625) $PN 2
J 0
(-2790 4605);
DISPLAY 0.617021 (-2790 4605);
PAINT WHITE (-2790 4605);
FORCEPROP 1 LAST MATERIAL X6S
J 0
(-2750 4625);
DISPLAY 0.617021 (-2750 4625);
PAINT SKYBLUE (-2750 4625);
FORCEPROP 2 LAST CDS_LOCATION C2M21
J 0
(-2750 4825);
DISPLAY 0.617021 (-2750 4825);
PAINT AQUA (-2750 4825);
DISPLAY INVISIBLE (-2750 4825);
FORCEPROP 0 LAST BOM_COST SB
J 0
(-2750 5025);
DISPLAY 1.021277 (-2750 5025);
PAINT ORANGE (-2750 5025);
DISPLAY INVISIBLE (-2750 5025);
FORCEPROP 2 LAST CDS_LIB dev_discrete
J 0
(-2800 4725);
PAINT ORANGE (-2800 4725);
DISPLAY INVISIBLE (-2800 4725);
FORCEPROP 2 LAST CDS_SEC 1
J 0
(-2750 4925);
PAINT MONO (-2750 4925);
DISPLAY INVISIBLE (-2750 4925);
FORCEPROP 2 LAST $SEC 1
J 0
(-2750 4925);
DISPLAY 0.914894 (-2750 4925);
PAINT MONO (-2750 4925);
DISPLAY INVISIBLE (-2750 4925);
FORCEPROP 1 LAST PATH I28
J 0
(-2750 4875);
DISPLAY 0.978723 (-2750 4875);
PAINT WHITE (-2750 4875);
DISPLAY INVISIBLE (-2750 4875);
FORCEPROP 0 LAST ROOM SB_DECOUPLING
J 0
(-2750 4925);
DISPLAY 1.021277 (-2750 4925);
PAINT ORANGE (-2750 4925);
DISPLAY INVISIBLE (-2750 4925);
FORCEADD CAP_A..1
(-3175 4725);
FORCEPROP 1 LAST LOCATION C2M18
J 0
(-3125 4825);
DISPLAY 0.617021 (-3125 4825);
PAINT AQUA (-3125 4825);
FORCEPROP 1 LAST PART_NUMBER D97712-004
J 0
(-3125 4575);
DISPLAY 0.617021 (-3125 4575);
PAINT BLUE (-3125 4575);
FORCEPROP 1 LAST VALUE 1.0UF
J 0
(-3125 4775);
DISPLAY 0.617021 (-3125 4775);
PAINT SKYBLUE (-3125 4775);
FORCEPROP 1 LAST TOLERANCE 10%
J 0
(-3125 4675);
DISPLAY 0.617021 (-3125 4675);
PAINT SKYBLUE (-3125 4675);
FORCEPROP 1 LAST PACK_TYPE 0402V
J 0
(-3125 4525);
DISPLAY 0.617021 (-3125 4525);
PAINT SKYBLUE (-3125 4525);
FORCEPROP 1 LAST VOLTAGE 6.3V
J 0
(-3125 4725);
DISPLAY 0.617021 (-3125 4725);
PAINT SKYBLUE (-3125 4725);
FORCEPROP 1 LAST MATERIAL X6S
J 0
(-3125 4625);
DISPLAY 0.617021 (-3125 4625);
PAINT SKYBLUE (-3125 4625);
FORCEPROP 1 LASTPIN (-3175 4825) $PN 1
J 0
(-3165 4805);
DISPLAY 0.617021 (-3165 4805);
PAINT WHITE (-3165 4805);
FORCEPROP 1 LASTPIN (-3175 4625) $PN 2
J 0
(-3165 4605);
DISPLAY 0.617021 (-3165 4605);
PAINT WHITE (-3165 4605);
FORCEPROP 2 LAST CDS_LOCATION C2M18
J 0
(-3125 4825);
DISPLAY 0.617021 (-3125 4825);
PAINT AQUA (-3125 4825);
DISPLAY INVISIBLE (-3125 4825);
FORCEPROP 2 LAST BOM_COST SB
J 0
(-3125 4475);
PAINT MONO (-3125 4475);
DISPLAY INVISIBLE (-3125 4475);
FORCEPROP 2 LAST CDS_LIB dev_discrete
J 0
(-3175 4725);
PAINT ORANGE (-3175 4725);
DISPLAY INVISIBLE (-3175 4725);
FORCEPROP 2 LAST CDS_SEC 1
J 0
(-3125 4925);
DISPLAY 1.361702 (-3125 4925);
PAINT ORANGE (-3125 4925);
DISPLAY INVISIBLE (-3125 4925);
FORCEPROP 2 LAST $SEC 1
J 0
(-3125 4925);
DISPLAY 0.914894 (-3125 4925);
PAINT MONO (-3125 4925);
DISPLAY INVISIBLE (-3125 4925);
FORCEPROP 1 LAST PATH I29
J 0
(-3125 4875);
DISPLAY 0.978723 (-3125 4875);
PAINT WHITE (-3125 4875);
DISPLAY INVISIBLE (-3125 4875);
FORCEPROP 2 LAST ROOM SB_DECOUPLING
J 0
(-3175 4725);
PAINT WHITE (-3175 4725);
DISPLAY INVISIBLE (-3175 4725);
FORCEADD CAP_A..1
(50 4975);
FORCEPROP 1 LAST LOCATION C7B16
J 0
(100 5075);
DISPLAY 0.617021 (100 5075);
PAINT AQUA (100 5075);
FORCEPROP 1 LAST PART_NUMBER E15431-004
J 0
(100 4825);
DISPLAY 0.617021 (100 4825);
PAINT BLUE (100 4825);
FORCEPROP 1 LAST TOLERANCE 20%
J 0
(100 4925);
DISPLAY 0.617021 (100 4925);
PAINT SKYBLUE (100 4925);
FORCEPROP 1 LAST PACK_TYPE 0603V
J 0
(100 4775);
DISPLAY 0.617021 (100 4775);
PAINT SKYBLUE (100 4775);
FORCEPROP 1 LAST VOLTAGE 4V
J 0
(100 4975);
DISPLAY 0.617021 (100 4975);
PAINT SKYBLUE (100 4975);
FORCEPROP 1 LAST MATERIAL X6S
J 0
(100 4875);
DISPLAY 0.617021 (100 4875);
PAINT SKYBLUE (100 4875);
FORCEPROP 1 LAST VALUE 22.0UF
J 0
(100 5025);
DISPLAY 0.617021 (100 5025);
PAINT SKYBLUE (100 5025);
FORCEPROP 2 LAST CDS_LOCATION C7B16
J 0
(100 5075);
DISPLAY 0.617021 (100 5075);
PAINT AQUA (100 5075);
DISPLAY INVISIBLE (100 5075);
FORCEPROP 2 LAST BOM_COST SB
J 0
(100 4725);
PAINT MONO (100 4725);
DISPLAY INVISIBLE (100 4725);
FORCEPROP 2 LAST CDS_LIB dev_discrete
J 0
(50 4975);
PAINT ORANGE (50 4975);
DISPLAY INVISIBLE (50 4975);
FORCEPROP 2 LAST CDS_SEC 1
J 0
(100 5175);
DISPLAY 1.361702 (100 5175);
PAINT ORANGE (100 5175);
DISPLAY INVISIBLE (100 5175);
FORCEPROP 2 LAST $SEC 1
J 0
(100 5175);
DISPLAY 0.914894 (100 5175);
PAINT MONO (100 5175);
DISPLAY INVISIBLE (100 5175);
FORCEPROP 1 LAST PATH I3
J 0
(100 5125);
DISPLAY 0.978723 (100 5125);
PAINT WHITE (100 5125);
DISPLAY INVISIBLE (100 5125);
FORCEPROP 2 LAST ROOM SB_DECOUPLING
J 0
(50 4975);
PAINT WHITE (50 4975);
DISPLAY INVISIBLE (50 4975);
FORCEPROP 1 LASTPIN (50 5075) $PN 1
J 0
(60 5055);
DISPLAY 1.063830 (60 5055);
PAINT WHITE (60 5055);
DISPLAY INVISIBLE (60 5055);
FORCEPROP 1 LASTPIN (50 4875) $PN 2
J 0
(60 4855);
DISPLAY 1.063830 (60 4855);
PAINT WHITE (60 4855);
DISPLAY INVISIBLE (60 4855);
FORCEADD GND..1
(-3350 4375);
FORCEPROP 3 LASTPIN (-3350 4425) SIG_NAME GND\g
J 0
(-3340 4435);
DISPLAY 0.659574 (-3340 4435);
PAINT MONO (-3340 4435);
DISPLAY INVISIBLE (-3340 4435);
FORCEPROP 1 LAST VOLTAGE 0
J 0
(-3350 4375);
PAINT SKYBLUE (-3350 4375);
DISPLAY INVISIBLE (-3350 4375);
FORCEPROP 2 LAST BOM_COST SB
J 0
(-3400 4450);
PAINT MONO (-3400 4450);
DISPLAY INVISIBLE (-3400 4450);
FORCEPROP 1 LAST SIZE 1B
J 0
(-3275 4325);
DISPLAY 1.404255 (-3275 4325);
PAINT GREEN (-3275 4325);
DISPLAY INVISIBLE (-3275 4325);
FORCEPROP 2 LAST CDS_LIB mstr_symbols
J 0
(-3350 4375);
PAINT ORANGE (-3350 4375);
DISPLAY INVISIBLE (-3350 4375);
FORCEPROP 1 LAST PATH I30
J 0
(-3275 4375);
DISPLAY 0.872340 (-3275 4375);
PAINT AQUA (-3275 4375);
DISPLAY INVISIBLE (-3275 4375);
FORCEPROP 2 LAST ROOM SB_DECOUPLING
J 0
(-3825 4450);
PAINT WHITE (-3825 4450);
DISPLAY INVISIBLE (-3825 4450);
FORCEPROP 1 LAST BODY_TYPE PLUMBING
J 0
(-3395 4332);
DISPLAY 0.340426 (-3395 4332);
PAINT GREEN (-3395 4332);
DISPLAY INVISIBLE (-3395 4332);
FORCEPROP 1 LAST HDL_POWER GND
J 0
(-3350 4525);
DISPLAY 1.404255 (-3350 4525);
PAINT GREEN (-3350 4525);
DISPLAY INVISIBLE (-3350 4525);
FORCEADD CAP_A..1
(-2850 3525);
FORCEPROP 1 LAST LOCATION C2M19
J 0
(-2800 3625);
DISPLAY 0.617021 (-2800 3625);
PAINT AQUA (-2800 3625);
FORCEPROP 1 LAST PART_NUMBER D97712-004
J 0
(-2800 3375);
DISPLAY 0.617021 (-2800 3375);
PAINT BLUE (-2800 3375);
FORCEPROP 1 LAST VALUE 1.0UF
J 0
(-2800 3575);
DISPLAY 0.617021 (-2800 3575);
PAINT SKYBLUE (-2800 3575);
FORCEPROP 1 LAST TOLERANCE 10%
J 0
(-2800 3475);
DISPLAY 0.617021 (-2800 3475);
PAINT SKYBLUE (-2800 3475);
FORCEPROP 1 LAST PACK_TYPE 0402V
J 0
(-2800 3325);
DISPLAY 0.617021 (-2800 3325);
PAINT SKYBLUE (-2800 3325);
FORCEPROP 1 LAST VOLTAGE 6.3V
J 0
(-2800 3525);
DISPLAY 0.617021 (-2800 3525);
PAINT SKYBLUE (-2800 3525);
FORCEPROP 1 LAST MATERIAL X6S
J 0
(-2800 3425);
DISPLAY 0.617021 (-2800 3425);
PAINT SKYBLUE (-2800 3425);
FORCEPROP 1 LASTPIN (-2850 3625) $PN 1
J 0
(-2840 3605);
DISPLAY 0.617021 (-2840 3605);
PAINT WHITE (-2840 3605);
FORCEPROP 1 LASTPIN (-2850 3425) $PN 2
J 0
(-2840 3405);
DISPLAY 0.617021 (-2840 3405);
PAINT WHITE (-2840 3405);
FORCEPROP 2 LAST CDS_LOCATION C2M19
J 0
(-2800 3625);
DISPLAY 0.617021 (-2800 3625);
PAINT AQUA (-2800 3625);
DISPLAY INVISIBLE (-2800 3625);
FORCEPROP 2 LAST BOM_COST SB
J 0
(-2800 3275);
PAINT MONO (-2800 3275);
DISPLAY INVISIBLE (-2800 3275);
FORCEPROP 2 LAST CDS_LIB dev_discrete
J 0
(-2850 3525);
PAINT ORANGE (-2850 3525);
DISPLAY INVISIBLE (-2850 3525);
FORCEPROP 2 LAST CDS_SEC 1
J 0
(-2800 3725);
DISPLAY 1.361702 (-2800 3725);
PAINT ORANGE (-2800 3725);
DISPLAY INVISIBLE (-2800 3725);
FORCEPROP 2 LAST $SEC 1
J 0
(-2800 3725);
DISPLAY 0.914894 (-2800 3725);
PAINT MONO (-2800 3725);
DISPLAY INVISIBLE (-2800 3725);
FORCEPROP 1 LAST PATH I31
J 0
(-2800 3675);
DISPLAY 0.978723 (-2800 3675);
PAINT WHITE (-2800 3675);
DISPLAY INVISIBLE (-2800 3675);
FORCEPROP 2 LAST ROOM SB_DECOUPLING
J 0
(-2850 3525);
PAINT WHITE (-2850 3525);
DISPLAY INVISIBLE (-2850 3525);
FORCEADD CAP_A..1
(-3225 3525);
FORCEPROP 1 LAST LOCATION C3M38
J 0
(-3175 3625);
DISPLAY 0.617021 (-3175 3625);
PAINT AQUA (-3175 3625);
FORCEPROP 1 LAST PART_NUMBER D97712-004
J 0
(-3175 3375);
DISPLAY 0.617021 (-3175 3375);
PAINT BLUE (-3175 3375);
FORCEPROP 1 LAST VALUE 1.0UF
J 0
(-3175 3575);
DISPLAY 0.617021 (-3175 3575);
PAINT SKYBLUE (-3175 3575);
FORCEPROP 1 LAST TOLERANCE 10%
J 0
(-3175 3475);
DISPLAY 0.617021 (-3175 3475);
PAINT SKYBLUE (-3175 3475);
FORCEPROP 1 LAST PACK_TYPE 0402V
J 0
(-3175 3325);
DISPLAY 0.617021 (-3175 3325);
PAINT SKYBLUE (-3175 3325);
FORCEPROP 1 LAST VOLTAGE 6.3V
J 0
(-3175 3525);
DISPLAY 0.617021 (-3175 3525);
PAINT SKYBLUE (-3175 3525);
FORCEPROP 1 LAST MATERIAL X6S
J 0
(-3175 3425);
DISPLAY 0.617021 (-3175 3425);
PAINT SKYBLUE (-3175 3425);
FORCEPROP 1 LASTPIN (-3225 3625) $PN 1
J 0
(-3215 3605);
DISPLAY 0.617021 (-3215 3605);
PAINT WHITE (-3215 3605);
FORCEPROP 1 LASTPIN (-3225 3425) $PN 2
J 0
(-3215 3405);
DISPLAY 0.617021 (-3215 3405);
PAINT WHITE (-3215 3405);
FORCEPROP 2 LAST CDS_LOCATION C3M38
J 0
(-3175 3625);
DISPLAY 0.617021 (-3175 3625);
PAINT AQUA (-3175 3625);
DISPLAY INVISIBLE (-3175 3625);
FORCEPROP 2 LAST BOM_COST SB
J 0
(-3175 3275);
PAINT MONO (-3175 3275);
DISPLAY INVISIBLE (-3175 3275);
FORCEPROP 2 LAST CDS_LIB dev_discrete
J 0
(-3225 3525);
PAINT ORANGE (-3225 3525);
DISPLAY INVISIBLE (-3225 3525);
FORCEPROP 2 LAST CDS_SEC 1
J 0
(-3175 3725);
DISPLAY 1.361702 (-3175 3725);
PAINT ORANGE (-3175 3725);
DISPLAY INVISIBLE (-3175 3725);
FORCEPROP 2 LAST $SEC 1
J 0
(-3175 3725);
DISPLAY 0.914894 (-3175 3725);
PAINT MONO (-3175 3725);
DISPLAY INVISIBLE (-3175 3725);
FORCEPROP 1 LAST PATH I32
J 0
(-3175 3675);
DISPLAY 0.978723 (-3175 3675);
PAINT WHITE (-3175 3675);
DISPLAY INVISIBLE (-3175 3675);
FORCEPROP 2 LAST ROOM SB_DECOUPLING
J 0
(-3225 3525);
PAINT WHITE (-3225 3525);
DISPLAY INVISIBLE (-3225 3525);
FORCEADD GND..1
(-3425 3175);
FORCEPROP 3 LASTPIN (-3425 3225) SIG_NAME GND\g
J 0
(-3415 3235);
DISPLAY 0.659574 (-3415 3235);
PAINT MONO (-3415 3235);
DISPLAY INVISIBLE (-3415 3235);
FORCEPROP 1 LAST VOLTAGE 0
J 0
(-3425 3175);
PAINT SKYBLUE (-3425 3175);
DISPLAY INVISIBLE (-3425 3175);
FORCEPROP 1 LAST SIZE 1B
J 0
(-3350 3125);
DISPLAY 1.404255 (-3350 3125);
PAINT GREEN (-3350 3125);
DISPLAY INVISIBLE (-3350 3125);
FORCEPROP 2 LAST CDS_LIB mstr_symbols
J 0
(-3425 3175);
PAINT ORANGE (-3425 3175);
DISPLAY INVISIBLE (-3425 3175);
FORCEPROP 2 LAST BOM_COST SB
J 0
(-3475 3250);
PAINT MONO (-3475 3250);
DISPLAY INVISIBLE (-3475 3250);
FORCEPROP 1 LAST PATH I33
J 0
(-3350 3175);
DISPLAY 0.872340 (-3350 3175);
PAINT AQUA (-3350 3175);
DISPLAY INVISIBLE (-3350 3175);
FORCEPROP 2 LAST ROOM SB_DECOUPLING
J 0
(-3900 3250);
PAINT WHITE (-3900 3250);
DISPLAY INVISIBLE (-3900 3250);
FORCEPROP 1 LAST BODY_TYPE PLUMBING
J 0
(-3470 3132);
DISPLAY 0.340426 (-3470 3132);
PAINT GREEN (-3470 3132);
DISPLAY INVISIBLE (-3470 3132);
FORCEPROP 1 LAST HDL_POWER GND
J 0
(-3425 3325);
DISPLAY 1.404255 (-3425 3325);
PAINT GREEN (-3425 3325);
DISPLAY INVISIBLE (-3425 3325);
FORCEADD CAP..1
(-2400 2025);
FORCEPROP 1 LAST LOCATION C2M17
J 0
(-2350 2125);
DISPLAY 0.617021 (-2350 2125);
PAINT AQUA (-2350 2125);
FORCEPROP 1 LAST PART_NUMBER C95333-006
J 0
(-2350 1875);
DISPLAY 0.617021 (-2350 1875);
PAINT BLUE (-2350 1875);
FORCEPROP 1 LAST VALUE 47UF
J 0
(-2350 2075);
DISPLAY 0.617021 (-2350 2075);
PAINT SKYBLUE (-2350 2075);
FORCEPROP 1 LAST TOLERANCE 20%
J 0
(-2350 1975);
DISPLAY 0.617021 (-2350 1975);
PAINT SKYBLUE (-2350 1975);
FORCEPROP 1 LAST PACK_TYPE 0805
J 0
(-2350 1825);
DISPLAY 0.617021 (-2350 1825);
PAINT SKYBLUE (-2350 1825);
FORCEPROP 1 LAST VOLTAGE 4V
J 0
(-2350 2025);
DISPLAY 0.617021 (-2350 2025);
PAINT SKYBLUE (-2350 2025);
FORCEPROP 1 LAST MATERIAL X6S
J 0
(-2350 1925);
DISPLAY 0.617021 (-2350 1925);
PAINT SKYBLUE (-2350 1925);
FORCEPROP 1 LASTPIN (-2400 1925) $PN 2
J 0
(-2390 1905);
DISPLAY 0.617021 (-2390 1905);
PAINT ORANGE (-2390 1905);
FORCEPROP 1 LASTPIN (-2400 2125) $PN 1
J 0
(-2390 2105);
DISPLAY 0.617021 (-2390 2105);
PAINT ORANGE (-2390 2105);
FORCEPROP 2 LAST CDS_LIB mstr_discrete
J 0
(-2400 2025);
PAINT ORANGE (-2400 2025);
DISPLAY INVISIBLE (-2400 2025);
FORCEPROP 2 LAST BOM_COST SB
J 0
(-2350 2225);
DISPLAY 1.361702 (-2350 2225);
PAINT ORANGE (-2350 2225);
DISPLAY INVISIBLE (-2350 2225);
FORCEPROP 2 LAST CDS_SEC 1
J 0
(-2350 2225);
DISPLAY 1.361702 (-2350 2225);
PAINT ORANGE (-2350 2225);
DISPLAY INVISIBLE (-2350 2225);
FORCEPROP 2 LAST $SEC 1
J 0
(-2350 2225);
DISPLAY 0.914894 (-2350 2225);
PAINT MONO (-2350 2225);
DISPLAY INVISIBLE (-2350 2225);
FORCEPROP 2 LAST CDS_LOCATION C2M17
J 0
(-2350 2125);
DISPLAY 0.617021 (-2350 2125);
PAINT AQUA (-2350 2125);
DISPLAY INVISIBLE (-2350 2125);
FORCEPROP 1 LAST PATH I34
J 0
(-2350 2175);
DISPLAY 0.978723 (-2350 2175);
PAINT WHITE (-2350 2175);
DISPLAY INVISIBLE (-2350 2175);
FORCEPROP 2 LAST ROOM SB_DECOUPLING
J 0
(-2350 2175);
DISPLAY 1.361702 (-2350 2175);
PAINT ORANGE (-2350 2175);
DISPLAY INVISIBLE (-2350 2175);
FORCEADD CAP..1
(-2800 2025);
FORCEPROP 1 LAST LOCATION C2M11
J 0
(-2750 2125);
DISPLAY 0.617021 (-2750 2125);
PAINT AQUA (-2750 2125);
FORCEPROP 1 LAST PART_NUMBER C95333-006
J 0
(-2750 1875);
DISPLAY 0.617021 (-2750 1875);
PAINT BLUE (-2750 1875);
FORCEPROP 1 LAST VALUE 47UF
J 0
(-2750 2075);
DISPLAY 0.617021 (-2750 2075);
PAINT SKYBLUE (-2750 2075);
FORCEPROP 1 LAST TOLERANCE 20%
J 0
(-2750 1975);
DISPLAY 0.617021 (-2750 1975);
PAINT SKYBLUE (-2750 1975);
FORCEPROP 1 LAST PACK_TYPE 0805
J 0
(-2750 1825);
DISPLAY 0.617021 (-2750 1825);
PAINT SKYBLUE (-2750 1825);
FORCEPROP 1 LAST VOLTAGE 4V
J 0
(-2750 2025);
DISPLAY 0.617021 (-2750 2025);
PAINT SKYBLUE (-2750 2025);
FORCEPROP 1 LAST MATERIAL X6S
J 0
(-2750 1925);
DISPLAY 0.617021 (-2750 1925);
PAINT SKYBLUE (-2750 1925);
FORCEPROP 1 LASTPIN (-2800 1925) $PN 2
J 0
(-2790 1905);
DISPLAY 0.617021 (-2790 1905);
PAINT WHITE (-2790 1905);
FORCEPROP 1 LASTPIN (-2800 2125) $PN 1
J 0
(-2790 2105);
DISPLAY 0.617021 (-2790 2105);
PAINT WHITE (-2790 2105);
FORCEPROP 2 LAST BOM_COST SB
J 0
(-2750 2225);
DISPLAY 1.361702 (-2750 2225);
PAINT ORANGE (-2750 2225);
DISPLAY INVISIBLE (-2750 2225);
FORCEPROP 2 LAST CDS_LIB mstr_discrete
J 0
(-2800 2025);
PAINT MONO (-2800 2025);
DISPLAY INVISIBLE (-2800 2025);
FORCEPROP 2 LAST CDS_SEC 1
J 0
(-2750 2225);
DISPLAY 1.361702 (-2750 2225);
PAINT ORANGE (-2750 2225);
DISPLAY INVISIBLE (-2750 2225);
FORCEPROP 2 LAST $SEC 1
J 0
(-2750 2225);
DISPLAY 0.914894 (-2750 2225);
PAINT MONO (-2750 2225);
DISPLAY INVISIBLE (-2750 2225);
FORCEPROP 2 LAST CDS_LOCATION C2M11
J 0
(-2750 2125);
DISPLAY 0.617021 (-2750 2125);
PAINT AQUA (-2750 2125);
DISPLAY INVISIBLE (-2750 2125);
FORCEPROP 1 LAST PATH I35
J 0
(-2750 2175);
DISPLAY 0.978723 (-2750 2175);
PAINT WHITE (-2750 2175);
DISPLAY INVISIBLE (-2750 2175);
FORCEPROP 2 LAST ROOM SB_DECOUPLING
J 0
(-2750 2175);
DISPLAY 1.361702 (-2750 2175);
PAINT ORANGE (-2750 2175);
DISPLAY INVISIBLE (-2750 2175);
FORCEADD P1V05_PCH_STBY..1
(-3025 2325);
FORCEPROP 3 LASTPIN (-3025 2275) SIG_NAME P1V05_PCH_STBY\g
J 0
(-3015 2285);
DISPLAY 0.659574 (-3015 2285);
PAINT MONO (-3015 2285);
DISPLAY INVISIBLE (-3015 2285);
FORCEPROP 1 LAST VOLTAGE 1.05V
J 0
(-3070 2282);
DISPLAY 0.340426 (-3070 2282);
PAINT SKYBLUE (-3070 2282);
DISPLAY INVISIBLE (-3070 2282);
FORCEPROP 2 LAST BOM_COST SB
J 0
(-3025 2425);
DISPLAY 1.361702 (-3025 2425);
PAINT ORANGE (-3025 2425);
DISPLAY INVISIBLE (-3025 2425);
FORCEPROP 2 LAST CDS_LIB mstr_symbols
J 0
(-3025 2325);
PAINT ORANGE (-3025 2325);
DISPLAY INVISIBLE (-3025 2325);
FORCEPROP 1 LAST PATH I36
J 0
(-2975 2350);
DISPLAY 0.872340 (-2975 2350);
PAINT AQUA (-2975 2350);
DISPLAY INVISIBLE (-2975 2350);
FORCEPROP 2 LAST ROOM SB_DECOUPLING
J 0
(-3025 2425);
DISPLAY 1.361702 (-3025 2425);
PAINT ORANGE (-3025 2425);
DISPLAY INVISIBLE (-3025 2425);
FORCEPROP 1 LAST BODY_TYPE PLUMBING
J 0
(-3070 2282);
DISPLAY 0.340426 (-3070 2282);
PAINT GREEN (-3070 2282);
DISPLAY INVISIBLE (-3070 2282);
FORCEPROP 1 LAST HDL_POWER P1V05_PCH_STBY
J 0
(-3025 2375);
DISPLAY 0.872340 (-3025 2375);
PAINT GREEN (-3025 2375);
DISPLAY INVISIBLE (-3025 2375);
FORCEADD CAP..1
(-3250 2025);
FORCEPROP 1 LAST LOCATION C8A13
J 0
(-3200 2125);
DISPLAY 0.617021 (-3200 2125);
PAINT AQUA (-3200 2125);
FORCEPROP 1 LAST PART_NUMBER C95333-006
J 0
(-3200 1875);
DISPLAY 0.617021 (-3200 1875);
PAINT BLUE (-3200 1875);
FORCEPROP 1 LAST VALUE 47UF
J 0
(-3200 2075);
DISPLAY 0.617021 (-3200 2075);
PAINT SKYBLUE (-3200 2075);
FORCEPROP 1 LAST TOLERANCE 20%
J 0
(-3200 1975);
DISPLAY 0.617021 (-3200 1975);
PAINT SKYBLUE (-3200 1975);
FORCEPROP 1 LAST PACK_TYPE 0805
J 0
(-3200 1825);
DISPLAY 0.617021 (-3200 1825);
PAINT SKYBLUE (-3200 1825);
FORCEPROP 1 LAST VOLTAGE 4V
J 0
(-3200 2025);
DISPLAY 0.617021 (-3200 2025);
PAINT SKYBLUE (-3200 2025);
FORCEPROP 1 LAST MATERIAL X6S
J 0
(-3200 1925);
DISPLAY 0.617021 (-3200 1925);
PAINT SKYBLUE (-3200 1925);
FORCEPROP 1 LASTPIN (-3250 1925) $PN 2
J 0
(-3240 1905);
DISPLAY 0.617021 (-3240 1905);
PAINT WHITE (-3240 1905);
FORCEPROP 1 LASTPIN (-3250 2125) $PN 1
J 0
(-3240 2105);
DISPLAY 0.617021 (-3240 2105);
PAINT WHITE (-3240 2105);
FORCEPROP 2 LAST CDS_LIB mstr_discrete
J 0
(-3250 2025);
PAINT MONO (-3250 2025);
DISPLAY INVISIBLE (-3250 2025);
FORCEPROP 2 LAST BOM_COST SB
J 0
(-3200 2225);
DISPLAY 1.361702 (-3200 2225);
PAINT ORANGE (-3200 2225);
DISPLAY INVISIBLE (-3200 2225);
FORCEPROP 2 LAST CDS_SEC 1
J 0
(-3200 2225);
DISPLAY 1.361702 (-3200 2225);
PAINT ORANGE (-3200 2225);
DISPLAY INVISIBLE (-3200 2225);
FORCEPROP 2 LAST $SEC 1
J 0
(-3200 2225);
DISPLAY 0.914894 (-3200 2225);
PAINT MONO (-3200 2225);
DISPLAY INVISIBLE (-3200 2225);
FORCEPROP 2 LAST CDS_LOCATION C8A13
J 0
(-3200 2125);
DISPLAY 0.617021 (-3200 2125);
PAINT AQUA (-3200 2125);
DISPLAY INVISIBLE (-3200 2125);
FORCEPROP 1 LAST PATH I37
J 0
(-3200 2175);
DISPLAY 0.978723 (-3200 2175);
PAINT WHITE (-3200 2175);
DISPLAY INVISIBLE (-3200 2175);
FORCEPROP 2 LAST ROOM SB_DECOUPLING
J 0
(-3200 2175);
DISPLAY 1.361702 (-3200 2175);
PAINT ORANGE (-3200 2175);
DISPLAY INVISIBLE (-3200 2175);
FORCEADD GND..1
(-3025 1650);
FORCEPROP 3 LASTPIN (-3025 1700) SIG_NAME GND\g
J 0
(-3015 1710);
DISPLAY 0.659574 (-3015 1710);
PAINT MONO (-3015 1710);
DISPLAY INVISIBLE (-3015 1710);
FORCEPROP 1 LAST VOLTAGE 0.0V
J 0
(-3070 1607);
DISPLAY 0.340426 (-3070 1607);
PAINT SKYBLUE (-3070 1607);
DISPLAY INVISIBLE (-3070 1607);
FORCEPROP 2 LAST BOM_COST SB
J 0
(-3000 1725);
DISPLAY 1.361702 (-3000 1725);
PAINT ORANGE (-3000 1725);
DISPLAY INVISIBLE (-3000 1725);
FORCEPROP 2 LAST CDS_LIB mstr_symbols
J 0
(-3025 1650);
PAINT MONO (-3025 1650);
DISPLAY INVISIBLE (-3025 1650);
FORCEPROP 1 LAST SIZE 1B
J 0
(-2950 1600);
DISPLAY 1.170213 (-2950 1600);
PAINT AQUA (-2950 1600);
DISPLAY INVISIBLE (-2950 1600);
FORCEPROP 1 LAST PATH I38
J 0
(-2950 1650);
DISPLAY 0.872340 (-2950 1650);
PAINT AQUA (-2950 1650);
DISPLAY INVISIBLE (-2950 1650);
FORCEPROP 2 LAST ROOM SB_DECOUPLING
J 0
(-3000 1725);
DISPLAY 1.361702 (-3000 1725);
PAINT ORANGE (-3000 1725);
DISPLAY INVISIBLE (-3000 1725);
FORCEPROP 1 LAST BODY_TYPE PLUMBING
J 0
(-3070 1607);
DISPLAY 0.340426 (-3070 1607);
PAINT GREEN (-3070 1607);
DISPLAY INVISIBLE (-3070 1607);
FORCEPROP 1 LAST HDL_POWER GND
J 0
(-3025 1800);
DISPLAY 1.170213 (-3025 1800);
PAINT GREEN (-3025 1800);
DISPLAY INVISIBLE (-3025 1800);
FORCEADD CAP_A..1
(-3550 4725);
FORCEPROP 1 LAST LOCATION C2M20
J 0
(-3500 4825);
DISPLAY 0.617021 (-3500 4825);
PAINT AQUA (-3500 4825);
FORCEPROP 1 LAST PART_NUMBER D97712-004
J 0
(-3500 4575);
DISPLAY 0.617021 (-3500 4575);
PAINT BLUE (-3500 4575);
FORCEPROP 1 LAST VALUE 1.0UF
J 0
(-3500 4775);
DISPLAY 0.617021 (-3500 4775);
PAINT SKYBLUE (-3500 4775);
FORCEPROP 1 LAST TOLERANCE 10%
J 0
(-3500 4675);
DISPLAY 0.617021 (-3500 4675);
PAINT SKYBLUE (-3500 4675);
FORCEPROP 1 LAST VOLTAGE 6.3V
J 0
(-3500 4725);
DISPLAY 0.617021 (-3500 4725);
PAINT SKYBLUE (-3500 4725);
FORCEPROP 1 LAST MATERIAL X6S
J 0
(-3500 4625);
DISPLAY 0.617021 (-3500 4625);
PAINT SKYBLUE (-3500 4625);
FORCEPROP 1 LASTPIN (-3550 4825) $PN 1
J 0
(-3540 4805);
DISPLAY 0.617021 (-3540 4805);
PAINT WHITE (-3540 4805);
FORCEPROP 1 LASTPIN (-3550 4625) $PN 2
J 0
(-3540 4605);
DISPLAY 0.617021 (-3540 4605);
PAINT WHITE (-3540 4605);
FORCEPROP 1 LAST PACK_TYPE 0402V
J 0
(-3500 4525);
DISPLAY 0.617021 (-3500 4525);
PAINT SKYBLUE (-3500 4525);
FORCEPROP 2 LAST CDS_LOCATION C2M20
J 0
(-3500 4825);
DISPLAY 0.617021 (-3500 4825);
PAINT AQUA (-3500 4825);
DISPLAY INVISIBLE (-3500 4825);
FORCEPROP 2 LAST BOM_COST SB
J 0
(-3500 4475);
PAINT MONO (-3500 4475);
DISPLAY INVISIBLE (-3500 4475);
FORCEPROP 2 LAST CDS_LIB dev_discrete
J 0
(-3550 4725);
PAINT ORANGE (-3550 4725);
DISPLAY INVISIBLE (-3550 4725);
FORCEPROP 2 LAST CDS_SEC 1
J 0
(-3500 4925);
DISPLAY 1.361702 (-3500 4925);
PAINT ORANGE (-3500 4925);
DISPLAY INVISIBLE (-3500 4925);
FORCEPROP 2 LAST $SEC 1
J 0
(-3500 4925);
DISPLAY 0.914894 (-3500 4925);
PAINT MONO (-3500 4925);
DISPLAY INVISIBLE (-3500 4925);
FORCEPROP 1 LAST PATH I39
J 0
(-3500 4875);
DISPLAY 0.978723 (-3500 4875);
PAINT WHITE (-3500 4875);
DISPLAY INVISIBLE (-3500 4875);
FORCEPROP 2 LAST ROOM SB_DECOUPLING
J 0
(-3550 4725);
PAINT WHITE (-3550 4725);
DISPLAY INVISIBLE (-3550 4725);
FORCEADD CAP_A..1
(-425 4975);
FORCEPROP 1 LAST LOCATION C7B21
J 0
(-375 5075);
DISPLAY 0.617021 (-375 5075);
PAINT AQUA (-375 5075);
FORCEPROP 1 LAST PART_NUMBER E15431-004
J 0
(-375 4825);
DISPLAY 0.617021 (-375 4825);
PAINT BLUE (-375 4825);
FORCEPROP 1 LAST VALUE 22.0UF
J 0
(-375 5025);
DISPLAY 0.617021 (-375 5025);
PAINT SKYBLUE (-375 5025);
FORCEPROP 1 LAST TOLERANCE 20%
J 0
(-375 4925);
DISPLAY 0.617021 (-375 4925);
PAINT SKYBLUE (-375 4925);
FORCEPROP 1 LAST PACK_TYPE 0603V
J 0
(-375 4775);
DISPLAY 0.617021 (-375 4775);
PAINT SKYBLUE (-375 4775);
FORCEPROP 1 LAST VOLTAGE 4V
J 0
(-375 4975);
DISPLAY 0.617021 (-375 4975);
PAINT SKYBLUE (-375 4975);
FORCEPROP 1 LAST MATERIAL X6S
J 0
(-375 4875);
DISPLAY 0.617021 (-375 4875);
PAINT SKYBLUE (-375 4875);
FORCEPROP 2 LAST CDS_LOCATION C7B21
J 0
(-375 5075);
DISPLAY 0.617021 (-375 5075);
PAINT AQUA (-375 5075);
DISPLAY INVISIBLE (-375 5075);
FORCEPROP 2 LAST BOM_COST SB
J 0
(-375 4725);
PAINT MONO (-375 4725);
DISPLAY INVISIBLE (-375 4725);
FORCEPROP 2 LAST CDS_LIB dev_discrete
J 0
(-425 4975);
PAINT ORANGE (-425 4975);
DISPLAY INVISIBLE (-425 4975);
FORCEPROP 2 LAST CDS_SEC 1
J 0
(-375 5175);
DISPLAY 1.361702 (-375 5175);
PAINT ORANGE (-375 5175);
DISPLAY INVISIBLE (-375 5175);
FORCEPROP 2 LAST $SEC 1
J 0
(-375 5175);
DISPLAY 0.914894 (-375 5175);
PAINT MONO (-375 5175);
DISPLAY INVISIBLE (-375 5175);
FORCEPROP 1 LAST PATH I4
J 0
(-375 5125);
DISPLAY 0.978723 (-375 5125);
PAINT WHITE (-375 5125);
DISPLAY INVISIBLE (-375 5125);
FORCEPROP 2 LAST ROOM SB_DECOUPLING
J 0
(-425 4975);
PAINT WHITE (-425 4975);
DISPLAY INVISIBLE (-425 4975);
FORCEPROP 1 LASTPIN (-425 5075) $PN 1
J 0
(-415 5055);
DISPLAY 1.063830 (-415 5055);
PAINT WHITE (-415 5055);
DISPLAY INVISIBLE (-415 5055);
FORCEPROP 1 LASTPIN (-425 4875) $PN 2
J 0
(-415 4855);
DISPLAY 1.063830 (-415 4855);
PAINT WHITE (-415 4855);
DISPLAY INVISIBLE (-415 4855);
FORCEADD CAP_A..1
(-3950 4725);
FORCEPROP 1 LAST PART_NUMBER D97712-004
J 0
(-3900 4575);
DISPLAY 0.617021 (-3900 4575);
PAINT BLUE (-3900 4575);
FORCEPROP 1 LAST LOCATION C2N13
J 0
(-3900 4825);
DISPLAY 0.617021 (-3900 4825);
PAINT AQUA (-3900 4825);
FORCEPROP 1 LAST VALUE 1.0UF
J 0
(-3900 4775);
DISPLAY 0.617021 (-3900 4775);
PAINT SKYBLUE (-3900 4775);
FORCEPROP 1 LAST TOLERANCE 10%
J 0
(-3900 4675);
DISPLAY 0.617021 (-3900 4675);
PAINT SKYBLUE (-3900 4675);
FORCEPROP 1 LAST VOLTAGE 6.3V
J 0
(-3900 4725);
DISPLAY 0.617021 (-3900 4725);
PAINT SKYBLUE (-3900 4725);
FORCEPROP 1 LAST MATERIAL X6S
J 0
(-3900 4625);
DISPLAY 0.617021 (-3900 4625);
PAINT SKYBLUE (-3900 4625);
FORCEPROP 1 LASTPIN (-3950 4825) $PN 1
J 0
(-3940 4805);
DISPLAY 0.617021 (-3940 4805);
PAINT WHITE (-3940 4805);
FORCEPROP 1 LASTPIN (-3950 4625) $PN 2
J 0
(-3940 4605);
DISPLAY 0.617021 (-3940 4605);
PAINT WHITE (-3940 4605);
FORCEPROP 1 LAST PACK_TYPE 0402V
J 0
(-3900 4525);
DISPLAY 0.617021 (-3900 4525);
PAINT SKYBLUE (-3900 4525);
FORCEPROP 2 LAST CDS_LOCATION C2N13
J 0
(-3900 4825);
DISPLAY 0.617021 (-3900 4825);
PAINT AQUA (-3900 4825);
DISPLAY INVISIBLE (-3900 4825);
FORCEPROP 2 LAST BOM_COST SB
J 0
(-3900 4475);
PAINT MONO (-3900 4475);
DISPLAY INVISIBLE (-3900 4475);
FORCEPROP 2 LAST CDS_LIB dev_discrete
J 0
(-3950 4725);
PAINT ORANGE (-3950 4725);
DISPLAY INVISIBLE (-3950 4725);
FORCEPROP 2 LAST CDS_SEC 1
J 0
(-3900 4925);
DISPLAY 1.361702 (-3900 4925);
PAINT ORANGE (-3900 4925);
DISPLAY INVISIBLE (-3900 4925);
FORCEPROP 2 LAST $SEC 1
J 0
(-3900 4925);
DISPLAY 0.914894 (-3900 4925);
PAINT MONO (-3900 4925);
DISPLAY INVISIBLE (-3900 4925);
FORCEPROP 1 LAST PATH I40
J 0
(-3900 4875);
DISPLAY 0.978723 (-3900 4875);
PAINT WHITE (-3900 4875);
DISPLAY INVISIBLE (-3900 4875);
FORCEPROP 2 LAST ROOM SB_DECOUPLING
J 0
(-3950 4725);
PAINT WHITE (-3950 4725);
DISPLAY INVISIBLE (-3950 4725);
FORCEADD CAP_A..1
(-4350 4725);
FORCEPROP 1 LAST LOCATION C2N2
J 0
(-4300 4825);
DISPLAY 0.617021 (-4300 4825);
PAINT AQUA (-4300 4825);
FORCEPROP 1 LAST VALUE 1.0UF
J 0
(-4300 4775);
DISPLAY 0.617021 (-4300 4775);
PAINT SKYBLUE (-4300 4775);
FORCEPROP 1 LAST TOLERANCE 10%
J 0
(-4300 4675);
DISPLAY 0.617021 (-4300 4675);
PAINT SKYBLUE (-4300 4675);
FORCEPROP 1 LAST PACK_TYPE 0402V
J 0
(-4300 4525);
DISPLAY 0.617021 (-4300 4525);
PAINT SKYBLUE (-4300 4525);
FORCEPROP 1 LAST VOLTAGE 6.3V
J 0
(-4300 4725);
DISPLAY 0.617021 (-4300 4725);
PAINT SKYBLUE (-4300 4725);
FORCEPROP 1 LAST MATERIAL X6S
J 0
(-4300 4625);
DISPLAY 0.617021 (-4300 4625);
PAINT SKYBLUE (-4300 4625);
FORCEPROP 1 LASTPIN (-4350 4825) $PN 1
J 0
(-4340 4805);
DISPLAY 0.617021 (-4340 4805);
PAINT WHITE (-4340 4805);
FORCEPROP 1 LASTPIN (-4350 4625) $PN 2
J 0
(-4340 4605);
DISPLAY 0.617021 (-4340 4605);
PAINT WHITE (-4340 4605);
FORCEPROP 1 LAST PART_NUMBER D97712-004
J 0
(-4300 4575);
DISPLAY 0.617021 (-4300 4575);
PAINT BLUE (-4300 4575);
FORCEPROP 2 LAST CDS_LOCATION C2N2
J 0
(-4300 4825);
DISPLAY 0.617021 (-4300 4825);
PAINT AQUA (-4300 4825);
DISPLAY INVISIBLE (-4300 4825);
FORCEPROP 2 LAST BOM_COST SB
J 0
(-4300 4475);
PAINT MONO (-4300 4475);
DISPLAY INVISIBLE (-4300 4475);
FORCEPROP 2 LAST CDS_LIB dev_discrete
J 0
(-4350 4725);
PAINT ORANGE (-4350 4725);
DISPLAY INVISIBLE (-4350 4725);
FORCEPROP 2 LAST CDS_SEC 1
J 0
(-4300 4925);
DISPLAY 1.361702 (-4300 4925);
PAINT ORANGE (-4300 4925);
DISPLAY INVISIBLE (-4300 4925);
FORCEPROP 2 LAST $SEC 1
J 0
(-4300 4925);
DISPLAY 0.914894 (-4300 4925);
PAINT MONO (-4300 4925);
DISPLAY INVISIBLE (-4300 4925);
FORCEPROP 1 LAST PATH I41
J 0
(-4300 4875);
DISPLAY 0.978723 (-4300 4875);
PAINT WHITE (-4300 4875);
DISPLAY INVISIBLE (-4300 4875);
FORCEPROP 2 LAST ROOM SB_DECOUPLING
J 0
(-4350 4725);
PAINT WHITE (-4350 4725);
DISPLAY INVISIBLE (-4350 4725);
FORCEADD CAP_A..1
(-3600 3525);
FORCEPROP 1 LAST LOCATION C3M43
J 0
(-3550 3625);
DISPLAY 0.617021 (-3550 3625);
PAINT AQUA (-3550 3625);
FORCEPROP 1 LAST PART_NUMBER D97712-004
J 0
(-3550 3375);
DISPLAY 0.617021 (-3550 3375);
PAINT BLUE (-3550 3375);
FORCEPROP 1 LAST VALUE 1.0UF
J 0
(-3550 3575);
DISPLAY 0.617021 (-3550 3575);
PAINT SKYBLUE (-3550 3575);
FORCEPROP 1 LAST TOLERANCE 10%
J 0
(-3550 3475);
DISPLAY 0.617021 (-3550 3475);
PAINT SKYBLUE (-3550 3475);
FORCEPROP 1 LAST PACK_TYPE 0402V
J 0
(-3550 3325);
DISPLAY 0.617021 (-3550 3325);
PAINT SKYBLUE (-3550 3325);
FORCEPROP 1 LAST VOLTAGE 6.3V
J 0
(-3550 3525);
DISPLAY 0.617021 (-3550 3525);
PAINT SKYBLUE (-3550 3525);
FORCEPROP 1 LAST MATERIAL X6S
J 0
(-3550 3425);
DISPLAY 0.617021 (-3550 3425);
PAINT SKYBLUE (-3550 3425);
FORCEPROP 1 LASTPIN (-3600 3625) $PN 1
J 0
(-3590 3605);
DISPLAY 0.617021 (-3590 3605);
PAINT WHITE (-3590 3605);
FORCEPROP 1 LASTPIN (-3600 3425) $PN 2
J 0
(-3590 3405);
DISPLAY 0.617021 (-3590 3405);
PAINT WHITE (-3590 3405);
FORCEPROP 2 LAST CDS_LOCATION C3M43
J 0
(-3550 3625);
DISPLAY 0.617021 (-3550 3625);
PAINT AQUA (-3550 3625);
DISPLAY INVISIBLE (-3550 3625);
FORCEPROP 2 LAST BOM_COST SB
J 0
(-3550 3275);
PAINT MONO (-3550 3275);
DISPLAY INVISIBLE (-3550 3275);
FORCEPROP 2 LAST CDS_LIB dev_discrete
J 0
(-3600 3525);
PAINT ORANGE (-3600 3525);
DISPLAY INVISIBLE (-3600 3525);
FORCEPROP 2 LAST CDS_SEC 1
J 0
(-3550 3725);
DISPLAY 1.361702 (-3550 3725);
PAINT ORANGE (-3550 3725);
DISPLAY INVISIBLE (-3550 3725);
FORCEPROP 2 LAST $SEC 1
J 0
(-3550 3725);
DISPLAY 0.914894 (-3550 3725);
PAINT MONO (-3550 3725);
DISPLAY INVISIBLE (-3550 3725);
FORCEPROP 1 LAST PATH I42
J 0
(-3550 3675);
DISPLAY 0.978723 (-3550 3675);
PAINT WHITE (-3550 3675);
DISPLAY INVISIBLE (-3550 3675);
FORCEPROP 2 LAST ROOM SB_DECOUPLING
J 0
(-3600 3525);
PAINT WHITE (-3600 3525);
DISPLAY INVISIBLE (-3600 3525);
FORCEADD CAP_A..1
(-4000 3525);
FORCEPROP 1 LAST LOCATION C2N7
J 0
(-3950 3625);
DISPLAY 0.617021 (-3950 3625);
PAINT AQUA (-3950 3625);
FORCEPROP 1 LAST PART_NUMBER D97712-004
J 0
(-3950 3375);
DISPLAY 0.617021 (-3950 3375);
PAINT BLUE (-3950 3375);
FORCEPROP 1 LAST VALUE 1.0UF
J 0
(-3950 3575);
DISPLAY 0.617021 (-3950 3575);
PAINT SKYBLUE (-3950 3575);
FORCEPROP 1 LAST TOLERANCE 10%
J 0
(-3950 3475);
DISPLAY 0.617021 (-3950 3475);
PAINT SKYBLUE (-3950 3475);
FORCEPROP 1 LAST PACK_TYPE 0402V
J 0
(-3950 3325);
DISPLAY 0.617021 (-3950 3325);
PAINT SKYBLUE (-3950 3325);
FORCEPROP 1 LAST VOLTAGE 6.3V
J 0
(-3950 3525);
DISPLAY 0.617021 (-3950 3525);
PAINT SKYBLUE (-3950 3525);
FORCEPROP 1 LAST MATERIAL X6S
J 0
(-3950 3425);
DISPLAY 0.617021 (-3950 3425);
PAINT SKYBLUE (-3950 3425);
FORCEPROP 1 LASTPIN (-4000 3625) $PN 1
J 0
(-3990 3605);
DISPLAY 0.617021 (-3990 3605);
PAINT WHITE (-3990 3605);
FORCEPROP 1 LASTPIN (-4000 3425) $PN 2
J 0
(-3990 3405);
DISPLAY 0.617021 (-3990 3405);
PAINT WHITE (-3990 3405);
FORCEPROP 2 LAST CDS_LOCATION C2N7
J 0
(-3950 3625);
DISPLAY 0.617021 (-3950 3625);
PAINT AQUA (-3950 3625);
DISPLAY INVISIBLE (-3950 3625);
FORCEPROP 2 LAST BOM_COST SB
J 0
(-3950 3275);
PAINT MONO (-3950 3275);
DISPLAY INVISIBLE (-3950 3275);
FORCEPROP 2 LAST CDS_LIB dev_discrete
J 0
(-4000 3525);
PAINT ORANGE (-4000 3525);
DISPLAY INVISIBLE (-4000 3525);
FORCEPROP 2 LAST CDS_SEC 1
J 0
(-3950 3725);
DISPLAY 1.361702 (-3950 3725);
PAINT ORANGE (-3950 3725);
DISPLAY INVISIBLE (-3950 3725);
FORCEPROP 2 LAST $SEC 1
J 0
(-3950 3725);
DISPLAY 0.914894 (-3950 3725);
PAINT MONO (-3950 3725);
DISPLAY INVISIBLE (-3950 3725);
FORCEPROP 1 LAST PATH I43
J 0
(-3950 3675);
DISPLAY 0.978723 (-3950 3675);
PAINT WHITE (-3950 3675);
DISPLAY INVISIBLE (-3950 3675);
FORCEPROP 2 LAST ROOM SB_DECOUPLING
J 0
(-4000 3525);
PAINT WHITE (-4000 3525);
DISPLAY INVISIBLE (-4000 3525);
FORCEADD CAP_A..1
(-4375 3525);
FORCEPROP 1 LAST LOCATION C3M39
J 0
(-4325 3625);
DISPLAY 0.617021 (-4325 3625);
PAINT AQUA (-4325 3625);
FORCEPROP 1 LAST PART_NUMBER D97712-004
J 0
(-4325 3375);
DISPLAY 0.617021 (-4325 3375);
PAINT BLUE (-4325 3375);
FORCEPROP 1 LAST VALUE 1.0UF
J 0
(-4325 3575);
DISPLAY 0.617021 (-4325 3575);
PAINT SKYBLUE (-4325 3575);
FORCEPROP 1 LAST TOLERANCE 10%
J 0
(-4325 3475);
DISPLAY 0.617021 (-4325 3475);
PAINT SKYBLUE (-4325 3475);
FORCEPROP 1 LAST PACK_TYPE 0402V
J 0
(-4325 3325);
DISPLAY 0.617021 (-4325 3325);
PAINT SKYBLUE (-4325 3325);
FORCEPROP 1 LAST VOLTAGE 6.3V
J 0
(-4325 3525);
DISPLAY 0.617021 (-4325 3525);
PAINT SKYBLUE (-4325 3525);
FORCEPROP 1 LAST MATERIAL X6S
J 0
(-4325 3425);
DISPLAY 0.617021 (-4325 3425);
PAINT SKYBLUE (-4325 3425);
FORCEPROP 1 LASTPIN (-4375 3625) $PN 1
J 0
(-4365 3605);
DISPLAY 0.617021 (-4365 3605);
PAINT WHITE (-4365 3605);
FORCEPROP 1 LASTPIN (-4375 3425) $PN 2
J 0
(-4365 3405);
DISPLAY 0.617021 (-4365 3405);
PAINT WHITE (-4365 3405);
FORCEPROP 2 LAST CDS_LOCATION C3M39
J 0
(-4325 3625);
DISPLAY 0.617021 (-4325 3625);
PAINT AQUA (-4325 3625);
DISPLAY INVISIBLE (-4325 3625);
FORCEPROP 2 LAST BOM_COST SB
J 0
(-4325 3275);
PAINT MONO (-4325 3275);
DISPLAY INVISIBLE (-4325 3275);
FORCEPROP 2 LAST CDS_LIB dev_discrete
J 0
(-4375 3525);
PAINT ORANGE (-4375 3525);
DISPLAY INVISIBLE (-4375 3525);
FORCEPROP 2 LAST CDS_SEC 1
J 0
(-4325 3725);
DISPLAY 1.361702 (-4325 3725);
PAINT ORANGE (-4325 3725);
DISPLAY INVISIBLE (-4325 3725);
FORCEPROP 2 LAST $SEC 1
J 0
(-4325 3725);
DISPLAY 0.914894 (-4325 3725);
PAINT MONO (-4325 3725);
DISPLAY INVISIBLE (-4325 3725);
FORCEPROP 1 LAST PATH I44
J 0
(-4325 3675);
DISPLAY 0.978723 (-4325 3675);
PAINT WHITE (-4325 3675);
DISPLAY INVISIBLE (-4325 3675);
FORCEPROP 2 LAST ROOM SB_DECOUPLING
J 0
(-4375 3525);
PAINT WHITE (-4375 3525);
DISPLAY INVISIBLE (-4375 3525);
FORCEADD CAP_A..1
(-4750 4725);
FORCEPROP 1 LAST VALUE 1.0UF
J 0
(-4700 4775);
DISPLAY 0.617021 (-4700 4775);
PAINT SKYBLUE (-4700 4775);
FORCEPROP 1 LAST PART_NUMBER D97712-004
J 0
(-4700 4575);
DISPLAY 0.617021 (-4700 4575);
PAINT BLUE (-4700 4575);
FORCEPROP 1 LAST TOLERANCE 10%
J 0
(-4700 4675);
DISPLAY 0.617021 (-4700 4675);
PAINT SKYBLUE (-4700 4675);
FORCEPROP 1 LAST PACK_TYPE 0402V
J 0
(-4700 4525);
DISPLAY 0.617021 (-4700 4525);
PAINT SKYBLUE (-4700 4525);
FORCEPROP 1 LAST MATERIAL X6S
J 0
(-4700 4625);
DISPLAY 0.617021 (-4700 4625);
PAINT SKYBLUE (-4700 4625);
FORCEPROP 1 LASTPIN (-4750 4825) $PN 1
J 0
(-4740 4805);
DISPLAY 0.617021 (-4740 4805);
PAINT WHITE (-4740 4805);
FORCEPROP 1 LASTPIN (-4750 4625) $PN 2
J 0
(-4740 4605);
DISPLAY 0.617021 (-4740 4605);
PAINT WHITE (-4740 4605);
FORCEPROP 1 LAST LOCATION C3M42
J 0
(-4700 4825);
DISPLAY 0.617021 (-4700 4825);
PAINT AQUA (-4700 4825);
FORCEPROP 1 LAST VOLTAGE 6.3V
J 0
(-4700 4725);
DISPLAY 0.617021 (-4700 4725);
PAINT SKYBLUE (-4700 4725);
FORCEPROP 2 LAST CDS_LOCATION C3M42
J 0
(-4700 4825);
DISPLAY 0.617021 (-4700 4825);
PAINT AQUA (-4700 4825);
DISPLAY INVISIBLE (-4700 4825);
FORCEPROP 2 LAST BOM_COST SB
J 0
(-4700 4475);
PAINT MONO (-4700 4475);
DISPLAY INVISIBLE (-4700 4475);
FORCEPROP 2 LAST CDS_LIB dev_discrete
J 0
(-4750 4725);
PAINT ORANGE (-4750 4725);
DISPLAY INVISIBLE (-4750 4725);
FORCEPROP 2 LAST CDS_SEC 1
J 0
(-4700 4925);
DISPLAY 1.361702 (-4700 4925);
PAINT ORANGE (-4700 4925);
DISPLAY INVISIBLE (-4700 4925);
FORCEPROP 2 LAST $SEC 1
J 0
(-4700 4925);
DISPLAY 0.914894 (-4700 4925);
PAINT MONO (-4700 4925);
DISPLAY INVISIBLE (-4700 4925);
FORCEPROP 1 LAST PATH I45
J 0
(-4700 4875);
DISPLAY 0.978723 (-4700 4875);
PAINT WHITE (-4700 4875);
DISPLAY INVISIBLE (-4700 4875);
FORCEPROP 2 LAST ROOM SB_DECOUPLING
J 0
(-4750 4725);
PAINT WHITE (-4750 4725);
DISPLAY INVISIBLE (-4750 4725);
FORCEADD P1V05_PCH_STBY..1
(-4600 3775);
FORCEPROP 3 LASTPIN (-4600 3725) SIG_NAME P1V05_PCH_STBY\g
J 0
(-4590 3735);
DISPLAY 0.659574 (-4590 3735);
PAINT MONO (-4590 3735);
DISPLAY INVISIBLE (-4590 3735);
FORCEPROP 1 LAST VOLTAGE 1.05V
J 0
(-4645 3732);
DISPLAY 0.340426 (-4645 3732);
PAINT SKYBLUE (-4645 3732);
DISPLAY INVISIBLE (-4645 3732);
FORCEPROP 2 LAST BOM_COST SB
J 0
(-4600 3925);
PAINT MONO (-4600 3925);
DISPLAY INVISIBLE (-4600 3925);
FORCEPROP 2 LAST CDS_LIB mstr_symbols
J 0
(-4600 3775);
PAINT ORANGE (-4600 3775);
DISPLAY INVISIBLE (-4600 3775);
FORCEPROP 1 LAST PATH I46
J 0
(-4550 3800);
DISPLAY 0.872340 (-4550 3800);
PAINT AQUA (-4550 3800);
DISPLAY INVISIBLE (-4550 3800);
FORCEPROP 2 LAST ROOM SB_DECOUPLING
J 0
(-4600 3875);
DISPLAY 1.361702 (-4600 3875);
PAINT WHITE (-4600 3875);
DISPLAY INVISIBLE (-4600 3875);
FORCEPROP 1 LAST BODY_TYPE PLUMBING
J 0
(-4645 3732);
DISPLAY 0.340426 (-4645 3732);
PAINT GREEN (-4645 3732);
DISPLAY INVISIBLE (-4645 3732);
FORCEPROP 1 LAST HDL_POWER P1V05_PCH_STBY
J 0
(-4600 3825);
DISPLAY 0.872340 (-4600 3825);
PAINT GREEN (-4600 3825);
DISPLAY INVISIBLE (-4600 3825);
FORCEADD CAP_A..1
(-4775 3525);
FORCEPROP 1 LAST LOCATION C2N8
J 0
(-4725 3625);
DISPLAY 0.617021 (-4725 3625);
PAINT AQUA (-4725 3625);
FORCEPROP 1 LAST PART_NUMBER D97712-004
J 0
(-4725 3375);
DISPLAY 0.617021 (-4725 3375);
PAINT BLUE (-4725 3375);
FORCEPROP 1 LAST VALUE 1.0UF
J 0
(-4725 3575);
DISPLAY 0.617021 (-4725 3575);
PAINT SKYBLUE (-4725 3575);
FORCEPROP 1 LAST TOLERANCE 10%
J 0
(-4725 3475);
DISPLAY 0.617021 (-4725 3475);
PAINT SKYBLUE (-4725 3475);
FORCEPROP 1 LAST PACK_TYPE 0402V
J 0
(-4725 3325);
DISPLAY 0.617021 (-4725 3325);
PAINT SKYBLUE (-4725 3325);
FORCEPROP 1 LAST VOLTAGE 6.3V
J 0
(-4725 3525);
DISPLAY 0.617021 (-4725 3525);
PAINT SKYBLUE (-4725 3525);
FORCEPROP 1 LAST MATERIAL X6S
J 0
(-4725 3425);
DISPLAY 0.617021 (-4725 3425);
PAINT SKYBLUE (-4725 3425);
FORCEPROP 1 LASTPIN (-4775 3625) $PN 1
J 0
(-4765 3605);
DISPLAY 0.617021 (-4765 3605);
PAINT WHITE (-4765 3605);
FORCEPROP 1 LASTPIN (-4775 3425) $PN 2
J 0
(-4765 3405);
DISPLAY 0.617021 (-4765 3405);
PAINT WHITE (-4765 3405);
FORCEPROP 2 LAST CDS_LOCATION C2N8
J 0
(-4725 3625);
DISPLAY 0.617021 (-4725 3625);
PAINT AQUA (-4725 3625);
DISPLAY INVISIBLE (-4725 3625);
FORCEPROP 2 LAST BOM_COST SB
J 0
(-4725 3275);
PAINT MONO (-4725 3275);
DISPLAY INVISIBLE (-4725 3275);
FORCEPROP 2 LAST CDS_LIB dev_discrete
J 0
(-4775 3525);
PAINT ORANGE (-4775 3525);
DISPLAY INVISIBLE (-4775 3525);
FORCEPROP 2 LAST CDS_SEC 1
J 0
(-4725 3725);
DISPLAY 1.361702 (-4725 3725);
PAINT ORANGE (-4725 3725);
DISPLAY INVISIBLE (-4725 3725);
FORCEPROP 2 LAST $SEC 1
J 0
(-4725 3725);
DISPLAY 0.914894 (-4725 3725);
PAINT MONO (-4725 3725);
DISPLAY INVISIBLE (-4725 3725);
FORCEPROP 1 LAST PATH I47
J 0
(-4725 3675);
DISPLAY 0.978723 (-4725 3675);
PAINT WHITE (-4725 3675);
DISPLAY INVISIBLE (-4725 3675);
FORCEPROP 2 LAST ROOM SB_DECOUPLING
J 0
(-4775 3525);
PAINT WHITE (-4775 3525);
DISPLAY INVISIBLE (-4775 3525);
FORCEADD CAP_A..1
(-4250 2100);
FORCEPROP 1 LAST LOCATION C2M13
J 0
(-4200 2200);
DISPLAY 0.617021 (-4200 2200);
PAINT AQUA (-4200 2200);
FORCEPROP 1 LAST PART_NUMBER E15431-004
J 0
(-4200 1950);
DISPLAY 0.617021 (-4200 1950);
PAINT BLUE (-4200 1950);
FORCEPROP 1 LAST VALUE 22.0UF
J 0
(-4200 2150);
DISPLAY 0.617021 (-4200 2150);
PAINT SKYBLUE (-4200 2150);
FORCEPROP 1 LAST TOLERANCE 20%
J 0
(-4200 2050);
DISPLAY 0.617021 (-4200 2050);
PAINT SKYBLUE (-4200 2050);
FORCEPROP 1 LAST PACK_TYPE 0603V
J 0
(-4200 1900);
DISPLAY 0.617021 (-4200 1900);
PAINT SKYBLUE (-4200 1900);
FORCEPROP 1 LAST VOLTAGE 4V
J 0
(-4200 2100);
DISPLAY 0.617021 (-4200 2100);
PAINT SKYBLUE (-4200 2100);
FORCEPROP 1 LAST MATERIAL X6S
J 0
(-4200 2000);
DISPLAY 0.617021 (-4200 2000);
PAINT SKYBLUE (-4200 2000);
FORCEPROP 1 LASTPIN (-4250 2200) $PN 1
J 0
(-4240 2180);
DISPLAY 0.617021 (-4240 2180);
PAINT ORANGE (-4240 2180);
FORCEPROP 1 LASTPIN (-4250 2000) $PN 2
J 0
(-4240 1980);
DISPLAY 0.617021 (-4240 1980);
PAINT ORANGE (-4240 1980);
FORCEPROP 2 LAST CDS_LOCATION C2M13
J 0
(-4200 2200);
DISPLAY 0.617021 (-4200 2200);
PAINT AQUA (-4200 2200);
DISPLAY INVISIBLE (-4200 2200);
FORCEPROP 2 LAST BOM_COST SB
J 0
(-4200 2300);
DISPLAY 1.361702 (-4200 2300);
PAINT ORANGE (-4200 2300);
DISPLAY INVISIBLE (-4200 2300);
FORCEPROP 2 LAST CDS_LIB dev_discrete
J 0
(-4250 2100);
PAINT ORANGE (-4250 2100);
DISPLAY INVISIBLE (-4250 2100);
FORCEPROP 2 LAST CDS_SEC 1
J 0
(-4200 2300);
DISPLAY 1.361702 (-4200 2300);
PAINT ORANGE (-4200 2300);
DISPLAY INVISIBLE (-4200 2300);
FORCEPROP 2 LAST $SEC 1
J 0
(-4200 2300);
DISPLAY 0.914894 (-4200 2300);
PAINT MONO (-4200 2300);
DISPLAY INVISIBLE (-4200 2300);
FORCEPROP 1 LAST PATH I48
J 0
(-4200 2250);
DISPLAY 0.978723 (-4200 2250);
PAINT WHITE (-4200 2250);
DISPLAY INVISIBLE (-4200 2250);
FORCEPROP 2 LAST ROOM SB_DECOUPLING
J 0
(-4200 2250);
DISPLAY 1.361702 (-4200 2250);
PAINT ORANGE (-4200 2250);
DISPLAY INVISIBLE (-4200 2250);
FORCEADD P1V05_PCH_STBY..1
(-4800 2400);
FORCEPROP 3 LASTPIN (-4800 2350) SIG_NAME P1V05_PCH_STBY\g
J 0
(-4790 2360);
DISPLAY 0.659574 (-4790 2360);
PAINT MONO (-4790 2360);
DISPLAY INVISIBLE (-4790 2360);
FORCEPROP 1 LAST VOLTAGE 1.05V
J 0
(-4845 2357);
DISPLAY 0.340426 (-4845 2357);
PAINT SKYBLUE (-4845 2357);
DISPLAY INVISIBLE (-4845 2357);
FORCEPROP 2 LAST BOM_COST SB
J 0
(-4800 2500);
DISPLAY 1.361702 (-4800 2500);
PAINT ORANGE (-4800 2500);
DISPLAY INVISIBLE (-4800 2500);
FORCEPROP 2 LAST CDS_LIB mstr_symbols
J 0
(-4800 2400);
PAINT ORANGE (-4800 2400);
DISPLAY INVISIBLE (-4800 2400);
FORCEPROP 1 LAST PATH I49
J 0
(-4750 2425);
DISPLAY 0.872340 (-4750 2425);
PAINT AQUA (-4750 2425);
DISPLAY INVISIBLE (-4750 2425);
FORCEPROP 2 LAST ROOM SB_DECOUPLING
J 0
(-4800 2500);
DISPLAY 1.361702 (-4800 2500);
PAINT ORANGE (-4800 2500);
DISPLAY INVISIBLE (-4800 2500);
FORCEPROP 1 LAST BODY_TYPE PLUMBING
J 0
(-4845 2357);
DISPLAY 0.340426 (-4845 2357);
PAINT GREEN (-4845 2357);
DISPLAY INVISIBLE (-4845 2357);
FORCEPROP 1 LAST HDL_POWER P1V05_PCH_STBY
J 0
(-4800 2450);
DISPLAY 0.872340 (-4800 2450);
PAINT GREEN (-4800 2450);
DISPLAY INVISIBLE (-4800 2450);
FORCEADD P1V05_PCH_STBY..1
(-600 5225);
FORCEPROP 3 LASTPIN (-600 5175) SIG_NAME P1V05_PCH_STBY\g
J 0
(-590 5185);
DISPLAY 0.659574 (-590 5185);
PAINT MONO (-590 5185);
DISPLAY INVISIBLE (-590 5185);
FORCEPROP 1 LAST VOLTAGE 1.05V
J 0
(-645 5182);
DISPLAY 0.340426 (-645 5182);
PAINT SKYBLUE (-645 5182);
DISPLAY INVISIBLE (-645 5182);
FORCEPROP 2 LAST BOM_COST SB
J 0
(-600 5375);
PAINT MONO (-600 5375);
DISPLAY INVISIBLE (-600 5375);
FORCEPROP 2 LAST CDS_LIB mstr_symbols
J 0
(-600 5225);
PAINT ORANGE (-600 5225);
DISPLAY INVISIBLE (-600 5225);
FORCEPROP 1 LAST PATH I5
J 0
(-550 5250);
DISPLAY 0.872340 (-550 5250);
PAINT AQUA (-550 5250);
DISPLAY INVISIBLE (-550 5250);
FORCEPROP 2 LAST ROOM SB_DECOUPLING
J 0
(-600 5325);
DISPLAY 1.361702 (-600 5325);
PAINT WHITE (-600 5325);
DISPLAY INVISIBLE (-600 5325);
FORCEPROP 1 LAST BODY_TYPE PLUMBING
J 0
(-645 5182);
DISPLAY 0.340426 (-645 5182);
PAINT GREEN (-645 5182);
DISPLAY INVISIBLE (-645 5182);
FORCEPROP 1 LAST HDL_POWER P1V05_PCH_STBY
J 0
(-600 5275);
DISPLAY 0.872340 (-600 5275);
PAINT GREEN (-600 5275);
DISPLAY INVISIBLE (-600 5275);
FORCEADD CAP_A..1
(-4650 2100);
FORCEPROP 1 LAST LOCATION C2N10
J 0
(-4600 2200);
DISPLAY 0.617021 (-4600 2200);
PAINT AQUA (-4600 2200);
FORCEPROP 1 LAST PART_NUMBER E15431-004
J 0
(-4600 1950);
DISPLAY 0.617021 (-4600 1950);
PAINT BLUE (-4600 1950);
FORCEPROP 1 LAST VALUE 22.0UF
J 0
(-4600 2150);
DISPLAY 0.617021 (-4600 2150);
PAINT SKYBLUE (-4600 2150);
FORCEPROP 1 LAST TOLERANCE 20%
J 0
(-4600 2050);
DISPLAY 0.617021 (-4600 2050);
PAINT SKYBLUE (-4600 2050);
FORCEPROP 1 LAST PACK_TYPE 0603V
J 0
(-4600 1900);
DISPLAY 0.617021 (-4600 1900);
PAINT SKYBLUE (-4600 1900);
FORCEPROP 1 LAST VOLTAGE 4V
J 0
(-4600 2100);
DISPLAY 0.617021 (-4600 2100);
PAINT SKYBLUE (-4600 2100);
FORCEPROP 1 LAST MATERIAL X6S
J 0
(-4600 2000);
DISPLAY 0.617021 (-4600 2000);
PAINT SKYBLUE (-4600 2000);
FORCEPROP 1 LASTPIN (-4650 2200) $PN 1
J 0
(-4640 2180);
DISPLAY 0.617021 (-4640 2180);
PAINT WHITE (-4640 2180);
FORCEPROP 1 LASTPIN (-4650 2000) $PN 2
J 0
(-4640 1980);
DISPLAY 0.617021 (-4640 1980);
PAINT WHITE (-4640 1980);
FORCEPROP 2 LAST CDS_LOCATION C2N10
J 0
(-4600 2200);
DISPLAY 0.617021 (-4600 2200);
PAINT AQUA (-4600 2200);
DISPLAY INVISIBLE (-4600 2200);
FORCEPROP 2 LAST BOM_COST SB
J 0
(-4600 2300);
DISPLAY 1.361702 (-4600 2300);
PAINT ORANGE (-4600 2300);
DISPLAY INVISIBLE (-4600 2300);
FORCEPROP 2 LAST CDS_LIB dev_discrete
J 0
(-4650 2100);
PAINT ORANGE (-4650 2100);
DISPLAY INVISIBLE (-4650 2100);
FORCEPROP 2 LAST CDS_SEC 1
J 0
(-4600 2300);
DISPLAY 1.361702 (-4600 2300);
PAINT ORANGE (-4600 2300);
DISPLAY INVISIBLE (-4600 2300);
FORCEPROP 2 LAST $SEC 1
J 0
(-4600 2300);
DISPLAY 0.914894 (-4600 2300);
PAINT MONO (-4600 2300);
DISPLAY INVISIBLE (-4600 2300);
FORCEPROP 1 LAST PATH I50
J 0
(-4600 2250);
DISPLAY 0.978723 (-4600 2250);
PAINT WHITE (-4600 2250);
DISPLAY INVISIBLE (-4600 2250);
FORCEPROP 2 LAST ROOM SB_DECOUPLING
J 0
(-4600 2250);
DISPLAY 1.361702 (-4600 2250);
PAINT ORANGE (-4600 2250);
DISPLAY INVISIBLE (-4600 2250);
FORCEADD GND..1
(-4800 1725);
FORCEPROP 3 LASTPIN (-4800 1775) SIG_NAME GND\g
J 0
(-4790 1785);
DISPLAY 0.659574 (-4790 1785);
PAINT MONO (-4790 1785);
DISPLAY INVISIBLE (-4790 1785);
FORCEPROP 1 LAST VOLTAGE 0.0V
J 0
(-4845 1682);
DISPLAY 0.340426 (-4845 1682);
PAINT SKYBLUE (-4845 1682);
DISPLAY INVISIBLE (-4845 1682);
FORCEPROP 2 LAST CDS_LIB mstr_symbols
J 0
(-4800 1725);
PAINT MONO (-4800 1725);
DISPLAY INVISIBLE (-4800 1725);
FORCEPROP 1 LAST SIZE 1B
J 0
(-4725 1675);
DISPLAY 1.170213 (-4725 1675);
PAINT AQUA (-4725 1675);
DISPLAY INVISIBLE (-4725 1675);
FORCEPROP 2 LAST BOM_COST SB
J 0
(-4775 1800);
DISPLAY 1.361702 (-4775 1800);
PAINT ORANGE (-4775 1800);
DISPLAY INVISIBLE (-4775 1800);
FORCEPROP 1 LAST PATH I51
J 0
(-4725 1725);
DISPLAY 0.872340 (-4725 1725);
PAINT AQUA (-4725 1725);
DISPLAY INVISIBLE (-4725 1725);
FORCEPROP 2 LAST ROOM SB_DECOUPLING
J 0
(-4775 1800);
DISPLAY 1.361702 (-4775 1800);
PAINT ORANGE (-4775 1800);
DISPLAY INVISIBLE (-4775 1800);
FORCEPROP 1 LAST BODY_TYPE PLUMBING
J 0
(-4845 1682);
DISPLAY 0.340426 (-4845 1682);
PAINT GREEN (-4845 1682);
DISPLAY INVISIBLE (-4845 1682);
FORCEPROP 1 LAST HDL_POWER GND
J 0
(-4800 1875);
DISPLAY 1.170213 (-4800 1875);
PAINT GREEN (-4800 1875);
DISPLAY INVISIBLE (-4800 1875);
FORCEADD CAP_A..1
(-5075 2100);
FORCEPROP 1 LAST LOCATION C2M12
J 0
(-5025 2200);
DISPLAY 0.617021 (-5025 2200);
PAINT AQUA (-5025 2200);
FORCEPROP 1 LAST PART_NUMBER E15431-004
J 0
(-5025 1950);
DISPLAY 0.617021 (-5025 1950);
PAINT BLUE (-5025 1950);
FORCEPROP 1 LAST VALUE 22.0UF
J 0
(-5025 2150);
DISPLAY 0.617021 (-5025 2150);
PAINT SKYBLUE (-5025 2150);
FORCEPROP 1 LAST TOLERANCE 20%
J 0
(-5025 2050);
DISPLAY 0.617021 (-5025 2050);
PAINT SKYBLUE (-5025 2050);
FORCEPROP 1 LAST PACK_TYPE 0603V
J 0
(-5025 1900);
DISPLAY 0.617021 (-5025 1900);
PAINT SKYBLUE (-5025 1900);
FORCEPROP 1 LAST VOLTAGE 4V
J 0
(-5025 2100);
DISPLAY 0.617021 (-5025 2100);
PAINT SKYBLUE (-5025 2100);
FORCEPROP 1 LAST MATERIAL X6S
J 0
(-5025 2000);
DISPLAY 0.617021 (-5025 2000);
PAINT SKYBLUE (-5025 2000);
FORCEPROP 1 LASTPIN (-5075 2200) $PN 1
J 0
(-5065 2180);
DISPLAY 0.617021 (-5065 2180);
PAINT WHITE (-5065 2180);
FORCEPROP 1 LASTPIN (-5075 2000) $PN 2
J 0
(-5065 1980);
DISPLAY 0.617021 (-5065 1980);
PAINT WHITE (-5065 1980);
FORCEPROP 2 LAST CDS_LOCATION C2M12
J 0
(-5025 2200);
DISPLAY 0.617021 (-5025 2200);
PAINT AQUA (-5025 2200);
DISPLAY INVISIBLE (-5025 2200);
FORCEPROP 2 LAST BOM_COST SB
J 0
(-5025 2300);
DISPLAY 1.361702 (-5025 2300);
PAINT ORANGE (-5025 2300);
DISPLAY INVISIBLE (-5025 2300);
FORCEPROP 2 LAST CDS_LIB dev_discrete
J 0
(-5075 2100);
PAINT ORANGE (-5075 2100);
DISPLAY INVISIBLE (-5075 2100);
FORCEPROP 2 LAST CDS_SEC 1
J 0
(-5025 2300);
DISPLAY 1.361702 (-5025 2300);
PAINT ORANGE (-5025 2300);
DISPLAY INVISIBLE (-5025 2300);
FORCEPROP 2 LAST $SEC 1
J 0
(-5025 2300);
DISPLAY 0.914894 (-5025 2300);
PAINT MONO (-5025 2300);
DISPLAY INVISIBLE (-5025 2300);
FORCEPROP 1 LAST PATH I52
J 0
(-5025 2250);
DISPLAY 0.978723 (-5025 2250);
PAINT WHITE (-5025 2250);
DISPLAY INVISIBLE (-5025 2250);
FORCEPROP 2 LAST ROOM SB_DECOUPLING
J 0
(-5025 2250);
DISPLAY 1.361702 (-5025 2250);
PAINT ORANGE (-5025 2250);
DISPLAY INVISIBLE (-5025 2250);
FORCEADD CAP_A..1
(-875 4975);
FORCEPROP 1 LAST LOCATION C7B20
J 0
(-825 5075);
DISPLAY 0.617021 (-825 5075);
PAINT AQUA (-825 5075);
FORCEPROP 1 LAST PART_NUMBER E15431-004
J 0
(-825 4825);
DISPLAY 0.617021 (-825 4825);
PAINT BLUE (-825 4825);
FORCEPROP 1 LAST TOLERANCE 20%
J 0
(-825 4925);
DISPLAY 0.617021 (-825 4925);
PAINT SKYBLUE (-825 4925);
FORCEPROP 1 LAST PACK_TYPE 0603V
J 0
(-825 4775);
DISPLAY 0.617021 (-825 4775);
PAINT SKYBLUE (-825 4775);
FORCEPROP 1 LAST VOLTAGE 4V
J 0
(-825 4975);
DISPLAY 0.617021 (-825 4975);
PAINT SKYBLUE (-825 4975);
FORCEPROP 1 LAST MATERIAL X6S
J 0
(-825 4875);
DISPLAY 0.617021 (-825 4875);
PAINT SKYBLUE (-825 4875);
FORCEPROP 1 LAST VALUE 22.0UF
J 0
(-825 5025);
DISPLAY 0.617021 (-825 5025);
PAINT SKYBLUE (-825 5025);
FORCEPROP 2 LAST CDS_LOCATION C7B20
J 0
(-825 5075);
DISPLAY 0.617021 (-825 5075);
PAINT AQUA (-825 5075);
DISPLAY INVISIBLE (-825 5075);
FORCEPROP 2 LAST BOM_COST SB
J 0
(-825 4725);
PAINT MONO (-825 4725);
DISPLAY INVISIBLE (-825 4725);
FORCEPROP 2 LAST CDS_LIB dev_discrete
J 0
(-875 4975);
PAINT ORANGE (-875 4975);
DISPLAY INVISIBLE (-875 4975);
FORCEPROP 2 LAST CDS_SEC 1
J 0
(-825 5175);
DISPLAY 1.361702 (-825 5175);
PAINT ORANGE (-825 5175);
DISPLAY INVISIBLE (-825 5175);
FORCEPROP 2 LAST $SEC 1
J 0
(-825 5175);
DISPLAY 0.914894 (-825 5175);
PAINT MONO (-825 5175);
DISPLAY INVISIBLE (-825 5175);
FORCEPROP 1 LAST PATH I6
J 0
(-825 5125);
DISPLAY 0.978723 (-825 5125);
PAINT WHITE (-825 5125);
DISPLAY INVISIBLE (-825 5125);
FORCEPROP 2 LAST ROOM SB_DECOUPLING
J 0
(-875 4975);
PAINT WHITE (-875 4975);
DISPLAY INVISIBLE (-875 4975);
FORCEPROP 1 LASTPIN (-875 5075) $PN 1
J 0
(-865 5055);
DISPLAY 1.063830 (-865 5055);
PAINT WHITE (-865 5055);
DISPLAY INVISIBLE (-865 5055);
FORCEPROP 1 LASTPIN (-875 4875) $PN 2
J 0
(-865 4855);
DISPLAY 1.063830 (-865 4855);
PAINT WHITE (-865 4855);
DISPLAY INVISIBLE (-865 4855);
FORCEADD CAP_A..1
(975 4025);
FORCEPROP 1 LAST LOCATION C7B23
J 0
(1025 4125);
DISPLAY 0.617021 (1025 4125);
PAINT AQUA (1025 4125);
FORCEPROP 1 LAST PART_NUMBER E15431-004
J 0
(1025 3875);
DISPLAY 0.617021 (1025 3875);
PAINT BLUE (1025 3875);
FORCEPROP 1 LAST VALUE 22.0UF
J 0
(1025 4075);
DISPLAY 0.617021 (1025 4075);
PAINT SKYBLUE (1025 4075);
FORCEPROP 1 LAST TOLERANCE 20%
J 0
(1025 3975);
DISPLAY 0.617021 (1025 3975);
PAINT SKYBLUE (1025 3975);
FORCEPROP 1 LAST PACK_TYPE 0603V
J 0
(1025 3825);
DISPLAY 0.617021 (1025 3825);
PAINT SKYBLUE (1025 3825);
FORCEPROP 1 LAST VOLTAGE 4V
J 0
(1025 4025);
DISPLAY 0.617021 (1025 4025);
PAINT SKYBLUE (1025 4025);
FORCEPROP 1 LAST MATERIAL X6S
J 0
(1025 3925);
DISPLAY 0.617021 (1025 3925);
PAINT SKYBLUE (1025 3925);
FORCEPROP 2 LAST CDS_LOCATION C7B23
J 0
(1025 4125);
DISPLAY 0.617021 (1025 4125);
PAINT AQUA (1025 4125);
DISPLAY INVISIBLE (1025 4125);
FORCEPROP 2 LAST BOM_COST SB
J 0
(1025 3775);
PAINT MONO (1025 3775);
DISPLAY INVISIBLE (1025 3775);
FORCEPROP 2 LAST CDS_LIB dev_discrete
J 0
(975 4025);
PAINT ORANGE (975 4025);
DISPLAY INVISIBLE (975 4025);
FORCEPROP 2 LAST CDS_SEC 1
J 0
(1025 4225);
DISPLAY 1.361702 (1025 4225);
PAINT ORANGE (1025 4225);
DISPLAY INVISIBLE (1025 4225);
FORCEPROP 2 LAST $SEC 1
J 0
(1025 4225);
DISPLAY 0.914894 (1025 4225);
PAINT MONO (1025 4225);
DISPLAY INVISIBLE (1025 4225);
FORCEPROP 1 LAST PATH I7
J 0
(1025 4175);
DISPLAY 0.978723 (1025 4175);
PAINT WHITE (1025 4175);
DISPLAY INVISIBLE (1025 4175);
FORCEPROP 2 LAST ROOM SB_DECOUPLING
J 0
(975 4025);
PAINT WHITE (975 4025);
DISPLAY INVISIBLE (975 4025);
FORCEPROP 1 LASTPIN (975 4125) $PN 1
J 0
(985 4105);
DISPLAY 1.063830 (985 4105);
PAINT WHITE (985 4105);
DISPLAY INVISIBLE (985 4105);
FORCEPROP 1 LASTPIN (975 3925) $PN 2
J 0
(985 3905);
DISPLAY 1.063830 (985 3905);
PAINT WHITE (985 3905);
DISPLAY INVISIBLE (985 3905);
FORCEADD CAP_A..1
(950 3025);
FORCEPROP 1 LAST LOCATION C8B10
J 0
(1000 3125);
DISPLAY 0.617021 (1000 3125);
PAINT AQUA (1000 3125);
FORCEPROP 1 LAST PART_NUMBER E15431-004
J 0
(1000 2875);
DISPLAY 0.617021 (1000 2875);
PAINT BLUE (1000 2875);
FORCEPROP 1 LAST VALUE 22.0UF
J 0
(1000 3075);
DISPLAY 0.617021 (1000 3075);
PAINT SKYBLUE (1000 3075);
FORCEPROP 1 LAST TOLERANCE 20%
J 0
(1000 2975);
DISPLAY 0.617021 (1000 2975);
PAINT SKYBLUE (1000 2975);
FORCEPROP 1 LAST PACK_TYPE 0603V
J 0
(1000 2825);
DISPLAY 0.617021 (1000 2825);
PAINT SKYBLUE (1000 2825);
FORCEPROP 1 LAST VOLTAGE 4V
J 0
(1000 3025);
DISPLAY 0.617021 (1000 3025);
PAINT SKYBLUE (1000 3025);
FORCEPROP 1 LAST MATERIAL X6S
J 0
(1000 2925);
DISPLAY 0.617021 (1000 2925);
PAINT SKYBLUE (1000 2925);
FORCEPROP 1 LASTPIN (950 3125) $PN 1
J 0
(960 3105);
DISPLAY 0.617021 (960 3105);
PAINT WHITE (960 3105);
FORCEPROP 1 LASTPIN (950 2925) $PN 2
J 0
(960 2905);
DISPLAY 0.617021 (960 2905);
PAINT WHITE (960 2905);
FORCEPROP 2 LAST CDS_LOCATION C8B10
J 0
(1000 3125);
DISPLAY 0.617021 (1000 3125);
PAINT AQUA (1000 3125);
DISPLAY INVISIBLE (1000 3125);
FORCEPROP 2 LAST BOM_COST SB
J 0
(1000 3225);
DISPLAY 1.361702 (1000 3225);
PAINT ORANGE (1000 3225);
DISPLAY INVISIBLE (1000 3225);
FORCEPROP 2 LAST CDS_LIB dev_discrete
J 0
(950 3025);
PAINT ORANGE (950 3025);
DISPLAY INVISIBLE (950 3025);
FORCEPROP 2 LAST CDS_SEC 1
J 0
(1000 3225);
DISPLAY 1.361702 (1000 3225);
PAINT ORANGE (1000 3225);
DISPLAY INVISIBLE (1000 3225);
FORCEPROP 2 LAST $SEC 1
J 0
(1000 3225);
DISPLAY 0.914894 (1000 3225);
PAINT MONO (1000 3225);
DISPLAY INVISIBLE (1000 3225);
FORCEPROP 1 LAST PATH I8
J 0
(1000 3175);
DISPLAY 0.978723 (1000 3175);
PAINT WHITE (1000 3175);
DISPLAY INVISIBLE (1000 3175);
FORCEPROP 2 LAST ROOM SB_DECOUPLING
J 0
(1000 3175);
DISPLAY 1.361702 (1000 3175);
PAINT ORANGE (1000 3175);
DISPLAY INVISIBLE (1000 3175);
FORCEADD GND..1
(275 4625);
FORCEPROP 3 LASTPIN (275 4675) SIG_NAME GND\g
J 0
(285 4685);
DISPLAY 0.659574 (285 4685);
PAINT MONO (285 4685);
DISPLAY INVISIBLE (285 4685);
FORCEPROP 1 LAST VOLTAGE 0
J 0
(275 4625);
PAINT SKYBLUE (275 4625);
DISPLAY INVISIBLE (275 4625);
FORCEPROP 1 LAST SIZE 1B
J 0
(350 4575);
DISPLAY 1.404255 (350 4575);
PAINT GREEN (350 4575);
DISPLAY INVISIBLE (350 4575);
FORCEPROP 2 LAST CDS_LIB mstr_symbols
J 0
(275 4625);
PAINT ORANGE (275 4625);
DISPLAY INVISIBLE (275 4625);
FORCEPROP 2 LAST BOM_COST SB
J 0
(225 4700);
PAINT MONO (225 4700);
DISPLAY INVISIBLE (225 4700);
FORCEPROP 1 LAST PATH I9
J 0
(350 4625);
DISPLAY 0.872340 (350 4625);
PAINT AQUA (350 4625);
DISPLAY INVISIBLE (350 4625);
FORCEPROP 2 LAST ROOM SB_DECOUPLING
J 0
(-200 4700);
PAINT WHITE (-200 4700);
DISPLAY INVISIBLE (-200 4700);
FORCEPROP 1 LAST BODY_TYPE PLUMBING
J 0
(230 4582);
DISPLAY 0.340426 (230 4582);
PAINT GREEN (230 4582);
DISPLAY INVISIBLE (230 4582);
FORCEPROP 1 LAST HDL_POWER GND
J 0
(275 4775);
DISPLAY 1.404255 (275 4775);
PAINT GREEN (275 4775);
DISPLAY INVISIBLE (275 4775);
FORCEADD CAD_NOTE..1
(-3200 1425);
FORCEPROP 0 LAST L2 
J 0
(-3350 1275);
DISPLAY 1.063830 (-3350 1275);
PAINT WHITE (-3350 1275);
FORCEPROP 0 LAST L1 PLACE CAPS ON THE SECONDARY SIDE OF BGA
J 0
(-3350 1300);
DISPLAY 1.063830 (-3350 1300);
PAINT WHITE (-3350 1300);
FORCEPROP 2 LAST CDS_LIB mstr_symbols
J 0
(-3200 1425);
PAINT ORANGE (-3200 1425);
DISPLAY INVISIBLE (-3200 1425);
FORCEPROP 2 LAST BOM_COST SB
J 0
(-3350 1375);
PAINT MONO (-3350 1375);
DISPLAY INVISIBLE (-3350 1375);
FORCEPROP 2 LAST ROOM SB_DECOUPLING
J 0
(-3350 1375);
PAINT WHITE (-3350 1375);
DISPLAY INVISIBLE (-3350 1375);
FORCEPROP 1 LAST COMMENT_BODY TRUE
J 0
(-3175 1525);
DISPLAY 1.319149 (-3175 1525);
PAINT GREEN (-3175 1525);
DISPLAY INVISIBLE (-3175 1525);
FORCEADD CAD_NOTE..1
(-4925 1450);
FORCEPROP 0 LAST L2 STYLE NEAR TO PIN.
J 0
(-5075 1250);
DISPLAY 1.063830 (-5075 1250);
PAINT WHITE (-5075 1250);
FORCEPROP 0 LAST L1 PLACE CAPS BSC
J 0
(-5075 1325);
DISPLAY 1.063830 (-5075 1325);
PAINT WHITE (-5075 1325);
FORCEPROP 2 LAST BOM_COST SB
J 0
(-5075 1400);
PAINT MONO (-5075 1400);
DISPLAY INVISIBLE (-5075 1400);
FORCEPROP 2 LAST CDS_LIB mstr_symbols
J 0
(-4925 1450);
PAINT ORANGE (-4925 1450);
DISPLAY INVISIBLE (-4925 1450);
FORCEPROP 2 LAST ROOM SB_DECOUPLING
J 0
(-5075 1400);
PAINT WHITE (-5075 1400);
DISPLAY INVISIBLE (-5075 1400);
FORCEPROP 1 LAST COMMENT_BODY TRUE
J 0
(-4900 1550);
DISPLAY 1.319149 (-4900 1550);
PAINT GREEN (-4900 1550);
DISPLAY INVISIBLE (-4900 1550);
FORCEADD DESIGN_NOTE..1
(1350 1400);
FORCEPROP 0 LAST L1 P1V05_PCH_STBY DECOUPLING CAPS
J 0
(1150 1275);
DISPLAY 1.063830 (1150 1275);
PAINT WHITE (1150 1275);
FORCEPROP 2 LAST BOM_COST SB
J 0
(1150 1325);
DISPLAY 1.361702 (1150 1325);
PAINT ORANGE (1150 1325);
DISPLAY INVISIBLE (1150 1325);
FORCEPROP 2 LAST CDS_LIB mstr_symbols
J 0
(1350 1400);
PAINT ORANGE (1350 1400);
DISPLAY INVISIBLE (1350 1400);
FORCEPROP 2 LAST ROOM SB_DECOUPLING
J 0
(1150 1325);
DISPLAY 1.361702 (1150 1325);
PAINT WHITE (1150 1325);
DISPLAY INVISIBLE (1150 1325);
FORCEPROP 1 LAST COMMENT_BODY TRUE
J 0
(1375 1500);
DISPLAY 1.319149 (1375 1500);
PAINT ORANGE (1375 1500);
DISPLAY INVISIBLE (1375 1500);
FORCEADD INTEL_CORP_BPAGE..1
(2650 500);
FORCEPROP 1 LAST CDS_CON_LAST_MODIFIED Fri Jun 16 17:48:50 2017
J 0
(1225 825);
PAINT ORANGE (1225 825);
DISPLAY INVISIBLE (1225 825);
FORCEPROP 1 LAST CUSTOM_TXT_CDS <CURRENT_DESIGN_SHEET> OF <TOTAL_DESIGN_SHEETS>
J 0
(2150 525);
PAINT ORANGE (2150 525);
FORCEPROP 1 LAST CUSTOM_TXT_CDS <CON_LAST_MODIFIED>
J 0
(-1350 600);
PAINT ORANGE (-1350 600);
FORCEPROP 2 LAST CUSTOM_TXT_CDS <XR_PAGE_TITLE>
J 0
(-5240 5750);
DISPLAY 0.638298 (-5240 5750);
PAINT PINK (-5240 5750);
DISPLAY INVISIBLE (-5240 5750);
FORCEPROP 1 LAST SCH_TITLE PCH DECOUPLING 2/3
J 0
(-5300 550);
DISPLAY 1.212766 (-5300 550);
PAINT ORANGE (-5300 550);
FORCEPROP 2 LAST CDS_LIB mstr_symbols
J 0
(2650 500);
PAINT MONO (2650 500);
DISPLAY INVISIBLE (2650 500);
FORCEPROP 2 LAST PAGE_BORDER TRUE
J 0
(-5240 5750);
DISPLAY 0.851064 (-5240 5750);
PAINT PINK (-5240 5750);
DISPLAY INVISIBLE (-5240 5750);
FORCEPROP 2 LAST ROOM WBG_DECOUPLING
J 0
(-5225 5800);
PAINT MONO (-5225 5800);
DISPLAY INVISIBLE (-5225 5800);
FORCEPROP 2 LAST CDS_XR_PAGE_TITLE CR-131 : @BASEBOARD_FAB2_LIB.BASEBOARD_FAB2(SCH_1):PAGE131
J 0
(-5240 5750);
DISPLAY 0.638298 (-5240 5750);
PAINT PINK (-5240 5750);
DISPLAY INVISIBLE (-5240 5750);
FORCEPROP 1 LAST COMMENT_BODY TRUE
J 0
(2662 512);
DISPLAY 0.468085 (2662 512);
PAINT GREEN (2662 512);
DISPLAY INVISIBLE (2662 512);
FORCEADD CAD_NOTE..1
(-900 1425);
FORCEPROP 0 LAST L2 EDGE OF THE PKG.
J 0
(-1050 1225);
DISPLAY 1.063830 (-1050 1225);
PAINT WHITE (-1050 1225);
FORCEPROP 0 LAST L1 PLACE CAPS ON THE
J 0
(-1050 1300);
DISPLAY 1.063830 (-1050 1300);
PAINT WHITE (-1050 1300);
FORCEPROP 2 LAST CDS_LIB mstr_symbols
J 0
(-900 1425);
PAINT ORANGE (-900 1425);
DISPLAY INVISIBLE (-900 1425);
FORCEPROP 2 LAST BOM_COST SB
J 0
(-1050 1375);
PAINT MONO (-1050 1375);
DISPLAY INVISIBLE (-1050 1375);
FORCEPROP 2 LAST ROOM SB_DECOUPLING
J 0
(-1050 1375);
PAINT WHITE (-1050 1375);
DISPLAY INVISIBLE (-1050 1375);
FORCEPROP 1 LAST COMMENT_BODY TRUE
J 0
(-875 1525);
DISPLAY 1.319149 (-875 1525);
PAINT GREEN (-875 1525);
DISPLAY INVISIBLE (-875 1525);
WIRE 16 -1 (275 3750)(275 3700);
WIRE 16 -1 (50 3750)(275 3750);
WIRE 16 -1 (275 3750)(500 3750);
WIRE 16 -1 (975 3750)(500 3750);
WIRE 16 -1 (500 3925)(500 3750);
WIRE 16 -1 (50 3750)(-425 3750);
WIRE 16 -1 (50 3925)(50 3750);
WIRE 16 -1 (-875 3750)(-425 3750);
WIRE 16 -1 (-425 3925)(-425 3750);
WIRE 16 -1 (975 3925)(975 3750);
WIRE 16 -1 (-875 3925)(-875 3750);
WIRE 16 -1 (-625 4200)(-625 4250);
WIRE 16 -1 (-625 4200)(-425 4200);
WIRE 16 -1 (-625 4200)(-875 4200);
WIRE 16 -1 (-875 4125)(-875 4200);
WIRE 16 -1 (-425 4200)(50 4200);
WIRE 16 -1 (-425 4125)(-425 4200);
WIRE 16 -1 (500 4200)(50 4200);
WIRE 16 -1 (50 4125)(50 4200);
WIRE 16 -1 (975 4200)(500 4200);
WIRE 16 -1 (500 4125)(500 4200);
WIRE 16 -1 (975 4125)(975 4200);
WIRE 16 -1 (-625 3275)(-625 3225);
WIRE 16 -1 (-400 3225)(-625 3225);
WIRE 16 -1 (-850 3225)(-625 3225);
WIRE 16 -1 (-850 3125)(-850 3225);
WIRE 16 -1 (50 3225)(-400 3225);
WIRE 16 -1 (-400 3125)(-400 3225);
WIRE 16 -1 (500 3225)(50 3225);
WIRE 16 -1 (50 3125)(50 3225);
WIRE 16 -1 (950 3225)(500 3225);
WIRE 16 -1 (500 3125)(500 3225);
WIRE 16 -1 (950 3225)(950 3125);
WIRE 16 -1 (275 2775)(275 2725);
WIRE 16 -1 (50 2775)(275 2775);
WIRE 16 -1 (500 2775)(275 2775);
WIRE 16 -1 (950 2775)(500 2775);
WIRE 16 -1 (500 2925)(500 2775);
WIRE 16 -1 (50 2775)(-400 2775);
WIRE 16 -1 (50 2925)(50 2775);
WIRE 16 -1 (-400 2775)(-850 2775);
WIRE 16 -1 (-400 2925)(-400 2775);
WIRE 16 -1 (950 2925)(950 2775);
WIRE 16 -1 (-850 2925)(-850 2775);
WIRE 16 -1 (-175 2275)(-175 2225);
WIRE 16 -1 (50 2225)(-175 2225);
WIRE 16 -1 (-175 2225)(-400 2225);
WIRE 16 -1 (-400 2125)(-400 2225);
WIRE 16 -1 (50 2125)(50 2225);
WIRE 16 -1 (-175 1775)(-175 1700);
WIRE 16 -1 (50 1775)(-175 1775);
WIRE 16 -1 (-175 1775)(-400 1775);
WIRE 16 -1 (-400 1925)(-400 1775);
WIRE 16 -1 (50 1925)(50 1775);
WIRE 16 -1 (-4575 4900)(-4575 4950);
WIRE 16 -1 (-4575 4900)(-4350 4900);
WIRE 16 -1 (-4750 4900)(-4575 4900);
WIRE 16 -1 (-4750 4825)(-4750 4900);
WIRE 16 -1 (-3950 4900)(-4350 4900);
WIRE 16 -1 (-4350 4825)(-4350 4900);
WIRE 16 -1 (-3550 4900)(-3950 4900);
WIRE 16 -1 (-3950 4825)(-3950 4900);
WIRE 16 -1 (-3175 4900)(-3550 4900);
WIRE 16 -1 (-3550 4825)(-3550 4900);
WIRE 16 -1 (-3175 4900)(-2800 4900);
WIRE 16 -1 (-3175 4825)(-3175 4900);
WIRE 16 -1 (-2800 4900)(-2375 4900);
WIRE 16 -1 (-2800 4900)(-2800 4825);
WIRE 16 -1 (-2375 4900)(-2375 4825);
WIRE 16 -1 (-3350 4475)(-3350 4425);
WIRE 16 -1 (-3350 4475)(-3550 4475);
WIRE 16 -1 (-3350 4475)(-3175 4475);
WIRE 16 -1 (-2800 4475)(-3175 4475);
WIRE 16 -1 (-3175 4625)(-3175 4475);
WIRE 16 -1 (-3550 4475)(-3950 4475);
WIRE 16 -1 (-3550 4625)(-3550 4475);
WIRE 16 -1 (-3950 4475)(-4350 4475);
WIRE 16 -1 (-3950 4625)(-3950 4475);
WIRE 16 -1 (-2375 4475)(-2800 4475);
WIRE 16 -1 (-2800 4625)(-2800 4475);
WIRE 16 -1 (-2375 4625)(-2375 4475);
WIRE 16 -1 (-4750 4475)(-4350 4475);
WIRE 16 -1 (-4350 4625)(-4350 4475);
WIRE 16 -1 (-4750 4625)(-4750 4475);
WIRE 16 -1 (-3425 3275)(-3425 3225);
WIRE 16 -1 (-3425 3275)(-3600 3275);
WIRE 16 -1 (-3425 3275)(-3225 3275);
WIRE 16 -1 (-2850 3275)(-3225 3275);
WIRE 16 -1 (-3225 3425)(-3225 3275);
WIRE 16 -1 (-3600 3275)(-4000 3275);
WIRE 16 -1 (-3600 3425)(-3600 3275);
WIRE 16 -1 (-4000 3275)(-4375 3275);
WIRE 16 -1 (-4000 3425)(-4000 3275);
WIRE 16 -1 (-2850 3425)(-2850 3275);
WIRE 16 -1 (-4775 3275)(-4375 3275);
WIRE 16 -1 (-4375 3425)(-4375 3275);
WIRE 16 -1 (-4775 3425)(-4775 3275);
WIRE 16 -1 (-3025 2275)(-3025 2225);
WIRE 16 -1 (-2800 2225)(-3025 2225);
WIRE 16 -1 (-3025 2225)(-3250 2225);
WIRE 16 -1 (-3250 2125)(-3250 2225);
WIRE 16 -1 (-2800 2225)(-2400 2225);
WIRE 16 -1 (-2800 2125)(-2800 2225);
WIRE 16 -1 (-2400 2125)(-2400 2225);
WIRE 16 -1 (-3025 1775)(-3025 1700);
WIRE 16 -1 (-2800 1775)(-3025 1775);
WIRE 16 -1 (-3025 1775)(-3250 1775);
WIRE 16 -1 (-3250 1925)(-3250 1775);
WIRE 16 -1 (-2800 1775)(-2400 1775);
WIRE 16 -1 (-2800 1925)(-2800 1775);
WIRE 16 -1 (-2400 1775)(-2400 1925);
WIRE 16 -1 (-4600 3700)(-4600 3725);
WIRE 16 -1 (-4600 3700)(-4375 3700);
WIRE 16 -1 (-4775 3700)(-4600 3700);
WIRE 16 -1 (-4775 3625)(-4775 3700);
WIRE 16 -1 (-4000 3700)(-4375 3700);
WIRE 16 -1 (-4375 3625)(-4375 3700);
WIRE 16 -1 (-3600 3700)(-4000 3700);
WIRE 16 -1 (-4000 3625)(-4000 3700);
WIRE 16 -1 (-3225 3700)(-3600 3700);
WIRE 16 -1 (-3600 3625)(-3600 3700);
WIRE 16 -1 (-3225 3700)(-2850 3700);
WIRE 16 -1 (-3225 3625)(-3225 3700);
WIRE 16 -1 (-2850 3625)(-2850 3700);
WIRE 16 -1 (-4800 2350)(-4800 2275);
WIRE 16 -1 (-4650 2275)(-4800 2275);
WIRE 16 -1 (-5075 2275)(-4800 2275);
WIRE 16 -1 (-5075 2200)(-5075 2275);
WIRE 16 -1 (-4650 2275)(-4250 2275);
WIRE 16 -1 (-4650 2200)(-4650 2275);
WIRE 16 -1 (-4250 2275)(-4250 2200);
WIRE 16 -1 (-600 5150)(-600 5175);
WIRE 16 -1 (-600 5150)(-425 5150);
WIRE 16 -1 (-600 5150)(-875 5150);
WIRE 16 -1 (-875 5075)(-875 5150);
WIRE 16 -1 (-425 5150)(50 5150);
WIRE 16 -1 (-425 5075)(-425 5150);
WIRE 16 -1 (500 5150)(50 5150);
WIRE 16 -1 (50 5075)(50 5150);
WIRE 16 -1 (975 5150)(500 5150);
WIRE 16 -1 (500 5075)(500 5150);
WIRE 16 -1 (975 5075)(975 5150);
WIRE 16 -1 (-4800 1850)(-4800 1775);
WIRE 16 -1 (-4800 1850)(-4650 1850);
WIRE 16 -1 (-4800 1850)(-5075 1850);
WIRE 16 -1 (-5075 2000)(-5075 1850);
WIRE 16 -1 (-4250 1850)(-4650 1850);
WIRE 16 -1 (-4650 2000)(-4650 1850);
WIRE 16 -1 (-4250 2000)(-4250 1850);
WIRE 16 -1 (275 4725)(275 4675);
WIRE 16 -1 (50 4725)(275 4725);
WIRE 16 -1 (275 4725)(500 4725);
WIRE 16 -1 (975 4725)(500 4725);
WIRE 16 -1 (500 4875)(500 4725);
WIRE 16 -1 (50 4725)(-425 4725);
WIRE 16 -1 (50 4875)(50 4725);
WIRE 16 -1 (-875 4725)(-425 4725);
WIRE 16 -1 (-425 4875)(-425 4725);
WIRE 16 -1 (975 4875)(975 4725);
WIRE 16 -1 (-875 4875)(-875 4725);
WIRE 16 273 (-1550 5400)(-1550 900);
DOT 1 (-3350 4475);
DOT 1 (-2800 4475);
DOT 1 (-3950 4900);
DOT 1 (-600 5150);
DOT 1 (500 5150);
DOT 1 (50 5150);
DOT 1 (-425 5150);
DOT 1 (-425 4725);
DOT 1 (50 4725);
DOT 1 (275 4725);
DOT 1 (500 4200);
DOT 1 (500 3750);
DOT 1 (275 3750);
DOT 1 (50 3750);
DOT 1 (50 4200);
DOT 1 (-425 4200);
DOT 1 (-425 3750);
DOT 1 (500 3225);
DOT 1 (275 2775);
DOT 1 (50 2775);
DOT 1 (50 3225);
DOT 1 (-400 3225);
DOT 1 (-400 2775);
DOT 1 (-625 4200);
DOT 1 (-625 3225);
DOT 1 (-175 2225);
DOT 1 (-175 1775);
DOT 1 (-2800 4900);
DOT 1 (-3550 4900);
DOT 1 (-4350 4900);
DOT 1 (-3175 4475);
DOT 1 (-3225 3700);
DOT 1 (-3225 3275);
DOT 1 (-3425 3275);
DOT 1 (-2800 2225);
DOT 1 (-2800 1775);
DOT 1 (-3025 1775);
DOT 1 (-3025 2225);
DOT 1 (-3550 4475);
DOT 1 (-3950 4475);
DOT 1 (-4350 4475);
DOT 1 (-4375 3700);
DOT 1 (-4000 3700);
DOT 1 (-3600 3700);
DOT 1 (-3600 3275);
DOT 1 (-4000 3275);
DOT 1 (-4375 3275);
DOT 1 (-4600 3700);
DOT 1 (-4650 2275);
DOT 1 (-4800 2275);
DOT 1 (-4650 1850);
DOT 1 (-4800 1850);
DOT 1 (500 4725);
DOT 1 (500 2775);
DOT 1 (-3175 4900);
DOT 1 (-4575 4900);
FORCENOTE
BOM_COST=SB
(-5288 817) 0;
DISPLAY LEFT (-5288 817);
DISPLAY 1.361702 (-5288 817);
PAINT PURPLE (-5288 817);
FORCENOTE
ROOM=LBG_DECOUPLING
(-5288 917) 0;
DISPLAY LEFT (-5288 917);
DISPLAY 1.361702 (-5288 917);
PAINT PURPLE (-5288 917);
QUIT
